FILE_TYPE = MACRO_DRAWING;
SET COLOR_WIRE YELLOW;
SET COLOR_PROP ORANGE;
SET COLOR_DOT WHITE;
SET COLOR_ARC YELLOW;
SET COLOR_BODY GREEN;
SET COLOR_NOTE PURPLE;
SET PROP_DISPLAY VALUE;
SET PAGE_NUMBER P73;
FORCEADD Q_CAP..1
(400 1075);
FORCEPROP 1 LAST LOCATION C3912
J 0
(450 1175);
DISPLAY 0.489362 (450 1175);
PAINT SKYBLUE (450 1175);
FORCEPROP 2 LAST $SEC 1
J 0
(450 1275);
DISPLAY 0.680851 (450 1275);
PAINT MONO (450 1275);
DISPLAY INVISIBLE (450 1275);
FORCEPROP 2 LAST CDS_SEC 1
J 0
(450 1275);
DISPLAY 1.021277 (450 1275);
DISPLAY INVISIBLE (450 1275);
FORCEPROP 1 LASTPIN (400 1175) $PN 1
J 0
(410 1155);
DISPLAY 0.489362 (410 1155);
FORCEPROP 1 LASTPIN (400 975) $PN 2
J 0
(410 955);
DISPLAY 0.489362 (410 955);
FORCEPROP 1 LAST MATERIAL X6S
J 0
(450 975);
DISPLAY 0.489362 (450 975);
PAINT SKYBLUE (450 975);
FORCEPROP 1 LAST TOLERANCE 20%
J 0
(450 1025);
DISPLAY 0.489362 (450 1025);
PAINT SKYBLUE (450 1025);
FORCEPROP 1 LAST VALUE 22UF
J 0
(450 1125);
DISPLAY 0.489362 (450 1125);
PAINT SKYBLUE (450 1125);
FORCEPROP 1 LAST VOLTAGE 4V
J 0
(450 1075);
DISPLAY 0.489362 (450 1075);
PAINT SKYBLUE (450 1075);
FORCEPROP 1 LAST PACK_TYPE C0402
J 0
(450 875);
DISPLAY 0.489362 (450 875);
PAINT SKYBLUE (450 875);
FORCEPROP 2 LAST CDS_LIB pure_quanta
J 0
(400 1075);
PAINT MONO (400 1075);
DISPLAY INVISIBLE (400 1075);
FORCEPROP 1 LAST PATH I1
J 0
(450 1225);
DISPLAY 0.978723 (450 1225);
PAINT WHITE (450 1225);
DISPLAY INVISIBLE (450 1225);
FORCEPROP 1 LAST PART_NUMBER CH622KMEB02
J 0
(450 925);
DISPLAY 0.489362 (450 925);
PAINT SKYBLUE (450 925);
DISPLAY INVISIBLE (450 925);
FORCEADD UNIVERSAL_POWER..1
(400 2075);
FORCEPROP 3 LASTPIN (400 2025) SIG_NAME PVDDCR_SOC_P1\g
J 0
(410 2035);
DISPLAY 0.659574 (410 2035);
PAINT MONO (410 2035);
DISPLAY INVISIBLE (410 2035);
FORCEPROP 1 LAST HDL_POWER PVDDCR_SOC_P1
J 1
(400 2125);
DISPLAY 0.489362 (400 2125);
PAINT GREEN (400 2125);
FORCEPROP 2 LAST CDS_LIB pure_quanta_power
J 0
(400 2075);
DISPLAY INVISIBLE (400 2075);
FORCEPROP 1 LAST PATH I10
J 0
(450 2100);
DISPLAY 0.872340 (450 2100);
PAINT AQUA (450 2100);
DISPLAY INVISIBLE (450 2100);
FORCEADD Q_CAP..1
(5450 2650);
FORCEPROP 1 LAST LOCATION C2486
J 0
(5500 2750);
DISPLAY 0.489362 (5500 2750);
PAINT SKYBLUE (5500 2750);
FORCEPROP 2 LAST $SEC 1
J 0
(5500 2850);
DISPLAY 0.680851 (5500 2850);
PAINT MONO (5500 2850);
DISPLAY INVISIBLE (5500 2850);
FORCEPROP 2 LAST CDS_SEC 1
J 0
(5500 2850);
DISPLAY 1.021277 (5500 2850);
DISPLAY INVISIBLE (5500 2850);
FORCEPROP 1 LASTPIN (5450 2750) $PN 1
J 0
(5460 2730);
DISPLAY 0.489362 (5460 2730);
FORCEPROP 1 LASTPIN (5450 2550) $PN 2
J 0
(5460 2530);
DISPLAY 0.489362 (5460 2530);
FORCEPROP 1 LAST MATERIAL X6S
J 0
(5500 2550);
DISPLAY 0.489362 (5500 2550);
PAINT SKYBLUE (5500 2550);
FORCEPROP 1 LAST TOLERANCE 20%
J 0
(5500 2600);
DISPLAY 0.489362 (5500 2600);
PAINT SKYBLUE (5500 2600);
FORCEPROP 1 LAST VALUE 22UF
J 0
(5500 2700);
DISPLAY 0.489362 (5500 2700);
PAINT SKYBLUE (5500 2700);
FORCEPROP 1 LAST VOLTAGE 4V
J 0
(5500 2650);
DISPLAY 0.489362 (5500 2650);
PAINT SKYBLUE (5500 2650);
FORCEPROP 1 LAST PACK_TYPE C0402
J 0
(5500 2450);
DISPLAY 0.489362 (5500 2450);
PAINT SKYBLUE (5500 2450);
FORCEPROP 2 LAST CDS_LIB pure_quanta
J 0
(5450 2650);
PAINT MONO (5450 2650);
DISPLAY INVISIBLE (5450 2650);
FORCEPROP 1 LAST PATH I100
J 0
(5500 2800);
DISPLAY 0.978723 (5500 2800);
PAINT WHITE (5500 2800);
DISPLAY INVISIBLE (5500 2800);
FORCEPROP 1 LAST PART_NUMBER CH622KMEB02
J 0
(5500 2500);
DISPLAY 0.489362 (5500 2500);
PAINT SKYBLUE (5500 2500);
DISPLAY INVISIBLE (5500 2500);
FORCEADD Q_CAP..1
(5900 2025);
FORCEPROP 1 LAST LOCATION C2491
J 0
(5950 2125);
DISPLAY 0.489362 (5950 2125);
PAINT SKYBLUE (5950 2125);
FORCEPROP 2 LAST $SEC 1
J 0
(5950 2225);
DISPLAY 0.680851 (5950 2225);
PAINT MONO (5950 2225);
DISPLAY INVISIBLE (5950 2225);
FORCEPROP 2 LAST CDS_SEC 1
J 0
(5950 2225);
DISPLAY 1.021277 (5950 2225);
DISPLAY INVISIBLE (5950 2225);
FORCEPROP 1 LASTPIN (5900 2125) $PN 1
J 0
(5910 2105);
DISPLAY 0.489362 (5910 2105);
FORCEPROP 1 LASTPIN (5900 1925) $PN 2
J 0
(5910 1905);
DISPLAY 0.489362 (5910 1905);
FORCEPROP 1 LAST MATERIAL X6S
J 0
(5950 1925);
DISPLAY 0.489362 (5950 1925);
PAINT SKYBLUE (5950 1925);
FORCEPROP 1 LAST TOLERANCE 20%
J 0
(5950 1975);
DISPLAY 0.489362 (5950 1975);
PAINT SKYBLUE (5950 1975);
FORCEPROP 1 LAST VALUE 22UF
J 0
(5950 2075);
DISPLAY 0.489362 (5950 2075);
PAINT SKYBLUE (5950 2075);
FORCEPROP 1 LAST VOLTAGE 4V
J 0
(5950 2025);
DISPLAY 0.489362 (5950 2025);
PAINT SKYBLUE (5950 2025);
FORCEPROP 1 LAST PACK_TYPE C0402
J 0
(5950 1825);
DISPLAY 0.489362 (5950 1825);
PAINT SKYBLUE (5950 1825);
FORCEPROP 2 LAST CDS_LIB pure_quanta
J 0
(5900 2025);
PAINT MONO (5900 2025);
DISPLAY INVISIBLE (5900 2025);
FORCEPROP 1 LAST PATH I101
J 0
(5950 2175);
DISPLAY 0.978723 (5950 2175);
PAINT WHITE (5950 2175);
DISPLAY INVISIBLE (5950 2175);
FORCEPROP 1 LAST PART_NUMBER CH622KMEB02
J 0
(5950 1875);
DISPLAY 0.489362 (5950 1875);
PAINT SKYBLUE (5950 1875);
DISPLAY INVISIBLE (5950 1875);
FORCEADD Q_CAP..1
(5900 2650);
FORCEPROP 1 LAST LOCATION C2490
J 0
(5950 2750);
DISPLAY 0.489362 (5950 2750);
PAINT SKYBLUE (5950 2750);
FORCEPROP 2 LAST $SEC 1
J 0
(5950 2850);
DISPLAY 0.680851 (5950 2850);
PAINT MONO (5950 2850);
DISPLAY INVISIBLE (5950 2850);
FORCEPROP 2 LAST CDS_SEC 1
J 0
(5950 2850);
DISPLAY 1.021277 (5950 2850);
DISPLAY INVISIBLE (5950 2850);
FORCEPROP 1 LASTPIN (5900 2750) $PN 1
J 0
(5910 2730);
DISPLAY 0.489362 (5910 2730);
FORCEPROP 1 LASTPIN (5900 2550) $PN 2
J 0
(5910 2530);
DISPLAY 0.489362 (5910 2530);
FORCEPROP 1 LAST MATERIAL X6S
J 0
(5950 2550);
DISPLAY 0.489362 (5950 2550);
PAINT SKYBLUE (5950 2550);
FORCEPROP 1 LAST TOLERANCE 20%
J 0
(5950 2600);
DISPLAY 0.489362 (5950 2600);
PAINT SKYBLUE (5950 2600);
FORCEPROP 1 LAST VALUE 22UF
J 0
(5950 2700);
DISPLAY 0.489362 (5950 2700);
PAINT SKYBLUE (5950 2700);
FORCEPROP 1 LAST VOLTAGE 4V
J 0
(5950 2650);
DISPLAY 0.489362 (5950 2650);
PAINT SKYBLUE (5950 2650);
FORCEPROP 1 LAST PACK_TYPE C0402
J 0
(5950 2450);
DISPLAY 0.489362 (5950 2450);
PAINT SKYBLUE (5950 2450);
FORCEPROP 2 LAST CDS_LIB pure_quanta
J 0
(5900 2650);
PAINT MONO (5900 2650);
DISPLAY INVISIBLE (5900 2650);
FORCEPROP 1 LAST PATH I102
J 0
(5950 2800);
DISPLAY 0.978723 (5950 2800);
PAINT WHITE (5950 2800);
DISPLAY INVISIBLE (5950 2800);
FORCEPROP 1 LAST PART_NUMBER CH622KMEB02
J 0
(5950 2500);
DISPLAY 0.489362 (5950 2500);
PAINT SKYBLUE (5950 2500);
DISPLAY INVISIBLE (5950 2500);
FORCEADD Q_CAP..1
(5450 3325);
FORCEPROP 1 LAST LOCATION C2485
J 0
(5500 3425);
DISPLAY 0.489362 (5500 3425);
PAINT SKYBLUE (5500 3425);
FORCEPROP 2 LAST $SEC 1
J 0
(5500 3525);
DISPLAY 0.680851 (5500 3525);
PAINT MONO (5500 3525);
DISPLAY INVISIBLE (5500 3525);
FORCEPROP 2 LAST CDS_SEC 1
J 0
(5500 3525);
DISPLAY 1.021277 (5500 3525);
DISPLAY INVISIBLE (5500 3525);
FORCEPROP 1 LASTPIN (5450 3425) $PN 1
J 0
(5460 3405);
DISPLAY 0.489362 (5460 3405);
FORCEPROP 1 LASTPIN (5450 3225) $PN 2
J 0
(5460 3205);
DISPLAY 0.489362 (5460 3205);
FORCEPROP 1 LAST MATERIAL X6S
J 0
(5500 3225);
DISPLAY 0.489362 (5500 3225);
PAINT SKYBLUE (5500 3225);
FORCEPROP 1 LAST TOLERANCE 20%
J 0
(5500 3275);
DISPLAY 0.489362 (5500 3275);
PAINT SKYBLUE (5500 3275);
FORCEPROP 1 LAST VALUE 22UF
J 0
(5500 3375);
DISPLAY 0.489362 (5500 3375);
PAINT SKYBLUE (5500 3375);
FORCEPROP 1 LAST VOLTAGE 4V
J 0
(5500 3325);
DISPLAY 0.489362 (5500 3325);
PAINT SKYBLUE (5500 3325);
FORCEPROP 1 LAST PACK_TYPE C0402
J 0
(5500 3125);
DISPLAY 0.489362 (5500 3125);
PAINT SKYBLUE (5500 3125);
FORCEPROP 2 LAST CDS_LIB pure_quanta
J 0
(5450 3325);
PAINT MONO (5450 3325);
DISPLAY INVISIBLE (5450 3325);
FORCEPROP 1 LAST PATH I103
J 0
(5500 3475);
DISPLAY 0.978723 (5500 3475);
PAINT WHITE (5500 3475);
DISPLAY INVISIBLE (5500 3475);
FORCEPROP 1 LAST PART_NUMBER CH622KMEB02
J 0
(5500 3175);
DISPLAY 0.489362 (5500 3175);
PAINT SKYBLUE (5500 3175);
DISPLAY INVISIBLE (5500 3175);
FORCEADD Q_CAP..1
(5900 3325);
FORCEPROP 1 LAST LOCATION C2489
J 0
(5950 3425);
DISPLAY 0.489362 (5950 3425);
PAINT SKYBLUE (5950 3425);
FORCEPROP 2 LAST $SEC 1
J 0
(5950 3525);
DISPLAY 0.680851 (5950 3525);
PAINT MONO (5950 3525);
DISPLAY INVISIBLE (5950 3525);
FORCEPROP 2 LAST CDS_SEC 1
J 0
(5950 3525);
DISPLAY 1.021277 (5950 3525);
DISPLAY INVISIBLE (5950 3525);
FORCEPROP 1 LASTPIN (5900 3425) $PN 1
J 0
(5910 3405);
DISPLAY 0.489362 (5910 3405);
FORCEPROP 1 LASTPIN (5900 3225) $PN 2
J 0
(5910 3205);
DISPLAY 0.489362 (5910 3205);
FORCEPROP 1 LAST MATERIAL X6S
J 0
(5950 3225);
DISPLAY 0.489362 (5950 3225);
PAINT SKYBLUE (5950 3225);
FORCEPROP 1 LAST TOLERANCE 20%
J 0
(5950 3275);
DISPLAY 0.489362 (5950 3275);
PAINT SKYBLUE (5950 3275);
FORCEPROP 1 LAST VALUE 22UF
J 0
(5950 3375);
DISPLAY 0.489362 (5950 3375);
PAINT SKYBLUE (5950 3375);
FORCEPROP 1 LAST VOLTAGE 4V
J 0
(5950 3325);
DISPLAY 0.489362 (5950 3325);
PAINT SKYBLUE (5950 3325);
FORCEPROP 1 LAST PACK_TYPE C0402
J 0
(5950 3125);
DISPLAY 0.489362 (5950 3125);
PAINT SKYBLUE (5950 3125);
FORCEPROP 2 LAST CDS_LIB pure_quanta
J 0
(5900 3325);
PAINT MONO (5900 3325);
DISPLAY INVISIBLE (5900 3325);
FORCEPROP 1 LAST PATH I104
J 0
(5950 3475);
DISPLAY 0.978723 (5950 3475);
PAINT WHITE (5950 3475);
DISPLAY INVISIBLE (5950 3475);
FORCEPROP 1 LAST PART_NUMBER CH622KMEB02
J 0
(5950 3175);
DISPLAY 0.489362 (5950 3175);
PAINT SKYBLUE (5950 3175);
DISPLAY INVISIBLE (5950 3175);
FORCEADD Q_CAP..1
(6350 1375);
FORCEPROP 1 LAST LOCATION C2497
J 0
(6400 1475);
DISPLAY 0.489362 (6400 1475);
PAINT SKYBLUE (6400 1475);
FORCEPROP 2 LAST $SEC 1
J 0
(6400 1575);
DISPLAY 0.680851 (6400 1575);
PAINT MONO (6400 1575);
DISPLAY INVISIBLE (6400 1575);
FORCEPROP 2 LAST CDS_SEC 1
J 0
(6400 1575);
DISPLAY 1.021277 (6400 1575);
DISPLAY INVISIBLE (6400 1575);
FORCEPROP 1 LASTPIN (6350 1475) $PN 1
J 0
(6360 1455);
DISPLAY 0.489362 (6360 1455);
FORCEPROP 1 LASTPIN (6350 1275) $PN 2
J 0
(6360 1255);
DISPLAY 0.489362 (6360 1255);
FORCEPROP 1 LAST MATERIAL X6S
J 0
(6400 1275);
DISPLAY 0.489362 (6400 1275);
PAINT SKYBLUE (6400 1275);
FORCEPROP 1 LAST TOLERANCE 20%
J 0
(6400 1325);
DISPLAY 0.489362 (6400 1325);
PAINT SKYBLUE (6400 1325);
FORCEPROP 1 LAST VALUE 22UF
J 0
(6400 1425);
DISPLAY 0.489362 (6400 1425);
PAINT SKYBLUE (6400 1425);
FORCEPROP 1 LAST VOLTAGE 4V
J 0
(6400 1375);
DISPLAY 0.489362 (6400 1375);
PAINT SKYBLUE (6400 1375);
FORCEPROP 1 LAST PACK_TYPE C0402
J 0
(6400 1175);
DISPLAY 0.489362 (6400 1175);
PAINT SKYBLUE (6400 1175);
FORCEPROP 2 LAST CDS_LIB pure_quanta
J 0
(6350 1375);
PAINT MONO (6350 1375);
DISPLAY INVISIBLE (6350 1375);
FORCEPROP 1 LAST PATH I105
J 0
(6400 1525);
DISPLAY 0.978723 (6400 1525);
PAINT WHITE (6400 1525);
DISPLAY INVISIBLE (6400 1525);
FORCEPROP 1 LAST PART_NUMBER CH622KMEB02
J 0
(6400 1225);
DISPLAY 0.489362 (6400 1225);
PAINT SKYBLUE (6400 1225);
DISPLAY INVISIBLE (6400 1225);
FORCEADD Q_CAP..1
(6800 1375);
FORCEPROP 1 LAST LOCATION C2502
J 0
(6850 1475);
DISPLAY 0.489362 (6850 1475);
PAINT SKYBLUE (6850 1475);
FORCEPROP 2 LAST $SEC 1
J 0
(6850 1575);
DISPLAY 0.680851 (6850 1575);
PAINT MONO (6850 1575);
DISPLAY INVISIBLE (6850 1575);
FORCEPROP 2 LAST CDS_SEC 1
J 0
(6850 1575);
DISPLAY 1.021277 (6850 1575);
DISPLAY INVISIBLE (6850 1575);
FORCEPROP 1 LASTPIN (6800 1475) $PN 1
J 0
(6810 1455);
DISPLAY 0.489362 (6810 1455);
FORCEPROP 1 LASTPIN (6800 1275) $PN 2
J 0
(6810 1255);
DISPLAY 0.489362 (6810 1255);
FORCEPROP 1 LAST MATERIAL X6S
J 0
(6850 1275);
DISPLAY 0.489362 (6850 1275);
PAINT SKYBLUE (6850 1275);
FORCEPROP 1 LAST TOLERANCE 20%
J 0
(6850 1325);
DISPLAY 0.489362 (6850 1325);
PAINT SKYBLUE (6850 1325);
FORCEPROP 1 LAST VALUE 22UF
J 0
(6850 1425);
DISPLAY 0.489362 (6850 1425);
PAINT SKYBLUE (6850 1425);
FORCEPROP 1 LAST VOLTAGE 4V
J 0
(6850 1375);
DISPLAY 0.489362 (6850 1375);
PAINT SKYBLUE (6850 1375);
FORCEPROP 1 LAST PACK_TYPE C0402
J 0
(6850 1175);
DISPLAY 0.489362 (6850 1175);
PAINT SKYBLUE (6850 1175);
FORCEPROP 2 LAST CDS_LIB pure_quanta
J 0
(6800 1375);
PAINT MONO (6800 1375);
DISPLAY INVISIBLE (6800 1375);
FORCEPROP 1 LAST PATH I106
J 0
(6850 1525);
DISPLAY 0.978723 (6850 1525);
PAINT WHITE (6850 1525);
DISPLAY INVISIBLE (6850 1525);
FORCEPROP 1 LAST PART_NUMBER CH622KMEB02
J 0
(6850 1225);
DISPLAY 0.489362 (6850 1225);
PAINT SKYBLUE (6850 1225);
DISPLAY INVISIBLE (6850 1225);
FORCEADD Q_CAP..1
(7250 1375);
FORCEPROP 1 LAST LOCATION C2506
J 0
(7300 1475);
DISPLAY 0.489362 (7300 1475);
PAINT SKYBLUE (7300 1475);
FORCEPROP 2 LAST $SEC 1
J 0
(7300 1575);
DISPLAY 0.680851 (7300 1575);
PAINT MONO (7300 1575);
DISPLAY INVISIBLE (7300 1575);
FORCEPROP 2 LAST CDS_SEC 1
J 0
(7300 1575);
DISPLAY 1.021277 (7300 1575);
DISPLAY INVISIBLE (7300 1575);
FORCEPROP 1 LASTPIN (7250 1475) $PN 1
J 0
(7260 1455);
DISPLAY 0.489362 (7260 1455);
FORCEPROP 1 LASTPIN (7250 1275) $PN 2
J 0
(7260 1255);
DISPLAY 0.489362 (7260 1255);
FORCEPROP 1 LAST MATERIAL X6S
J 0
(7300 1275);
DISPLAY 0.489362 (7300 1275);
PAINT SKYBLUE (7300 1275);
FORCEPROP 1 LAST TOLERANCE 20%
J 0
(7300 1325);
DISPLAY 0.489362 (7300 1325);
PAINT SKYBLUE (7300 1325);
FORCEPROP 1 LAST VALUE 22UF
J 0
(7300 1425);
DISPLAY 0.489362 (7300 1425);
PAINT SKYBLUE (7300 1425);
FORCEPROP 1 LAST VOLTAGE 4V
J 0
(7300 1375);
DISPLAY 0.489362 (7300 1375);
PAINT SKYBLUE (7300 1375);
FORCEPROP 1 LAST PACK_TYPE C0402
J 0
(7300 1175);
DISPLAY 0.489362 (7300 1175);
PAINT SKYBLUE (7300 1175);
FORCEPROP 2 LAST CDS_LIB pure_quanta
J 0
(7250 1375);
PAINT MONO (7250 1375);
DISPLAY INVISIBLE (7250 1375);
FORCEPROP 1 LAST PATH I107
J 0
(7300 1525);
DISPLAY 0.978723 (7300 1525);
PAINT WHITE (7300 1525);
DISPLAY INVISIBLE (7300 1525);
FORCEPROP 1 LAST PART_NUMBER CH622KMEB02
J 0
(7300 1225);
DISPLAY 0.489362 (7300 1225);
PAINT SKYBLUE (7300 1225);
DISPLAY INVISIBLE (7300 1225);
FORCEADD Q_CAP..1
(7700 1375);
FORCEPROP 1 LAST LOCATION C2115
J 0
(7750 1475);
DISPLAY 0.489362 (7750 1475);
PAINT SKYBLUE (7750 1475);
FORCEPROP 2 LAST $SEC 1
J 0
(7750 1575);
DISPLAY 0.680851 (7750 1575);
PAINT MONO (7750 1575);
DISPLAY INVISIBLE (7750 1575);
FORCEPROP 2 LAST CDS_SEC 1
J 0
(7750 1575);
DISPLAY 1.021277 (7750 1575);
DISPLAY INVISIBLE (7750 1575);
FORCEPROP 1 LASTPIN (7700 1475) $PN 1
J 0
(7710 1455);
DISPLAY 0.489362 (7710 1455);
FORCEPROP 1 LASTPIN (7700 1275) $PN 2
J 0
(7710 1255);
DISPLAY 0.489362 (7710 1255);
FORCEPROP 1 LAST MATERIAL X6S
J 0
(7750 1275);
DISPLAY 0.489362 (7750 1275);
PAINT SKYBLUE (7750 1275);
FORCEPROP 1 LAST TOLERANCE 20%
J 0
(7750 1325);
DISPLAY 0.489362 (7750 1325);
PAINT SKYBLUE (7750 1325);
FORCEPROP 1 LAST VALUE 22UF
J 0
(7750 1425);
DISPLAY 0.489362 (7750 1425);
PAINT SKYBLUE (7750 1425);
FORCEPROP 1 LAST VOLTAGE 4V
J 0
(7750 1375);
DISPLAY 0.489362 (7750 1375);
PAINT SKYBLUE (7750 1375);
FORCEPROP 1 LAST PACK_TYPE C0402
J 0
(7750 1175);
DISPLAY 0.489362 (7750 1175);
PAINT SKYBLUE (7750 1175);
FORCEPROP 2 LAST CDS_LIB pure_quanta
J 0
(7700 1375);
PAINT MONO (7700 1375);
DISPLAY INVISIBLE (7700 1375);
FORCEPROP 1 LAST PATH I108
J 0
(7750 1525);
DISPLAY 0.978723 (7750 1525);
PAINT WHITE (7750 1525);
DISPLAY INVISIBLE (7750 1525);
FORCEPROP 1 LAST PART_NUMBER CH622KMEB02
J 0
(7750 1225);
DISPLAY 0.489362 (7750 1225);
PAINT SKYBLUE (7750 1225);
DISPLAY INVISIBLE (7750 1225);
FORCEADD Q_CAP..1
(8150 1375);
FORCEPROP 1 LAST LOCATION C2121
J 0
(8200 1475);
DISPLAY 0.489362 (8200 1475);
PAINT SKYBLUE (8200 1475);
FORCEPROP 2 LAST $SEC 1
J 0
(8200 1575);
DISPLAY 0.680851 (8200 1575);
PAINT MONO (8200 1575);
DISPLAY INVISIBLE (8200 1575);
FORCEPROP 2 LAST CDS_SEC 1
J 0
(8200 1575);
DISPLAY 1.021277 (8200 1575);
DISPLAY INVISIBLE (8200 1575);
FORCEPROP 1 LASTPIN (8150 1475) $PN 1
J 0
(8160 1455);
DISPLAY 0.489362 (8160 1455);
FORCEPROP 1 LASTPIN (8150 1275) $PN 2
J 0
(8160 1255);
DISPLAY 0.489362 (8160 1255);
FORCEPROP 1 LAST MATERIAL X6S
J 0
(8200 1275);
DISPLAY 0.489362 (8200 1275);
PAINT SKYBLUE (8200 1275);
FORCEPROP 1 LAST TOLERANCE 20%
J 0
(8200 1325);
DISPLAY 0.489362 (8200 1325);
PAINT SKYBLUE (8200 1325);
FORCEPROP 1 LAST VALUE 22UF
J 0
(8200 1425);
DISPLAY 0.489362 (8200 1425);
PAINT SKYBLUE (8200 1425);
FORCEPROP 1 LAST VOLTAGE 4V
J 0
(8200 1375);
DISPLAY 0.489362 (8200 1375);
PAINT SKYBLUE (8200 1375);
FORCEPROP 1 LAST PACK_TYPE C0402
J 0
(8200 1175);
DISPLAY 0.489362 (8200 1175);
PAINT SKYBLUE (8200 1175);
FORCEPROP 2 LAST CDS_LIB pure_quanta
J 0
(8150 1375);
PAINT MONO (8150 1375);
DISPLAY INVISIBLE (8150 1375);
FORCEPROP 1 LAST PATH I109
J 0
(8200 1525);
DISPLAY 0.978723 (8200 1525);
PAINT WHITE (8200 1525);
DISPLAY INVISIBLE (8200 1525);
FORCEPROP 1 LAST PART_NUMBER CH622KMEB02
J 0
(8200 1225);
DISPLAY 0.489362 (8200 1225);
PAINT SKYBLUE (8200 1225);
DISPLAY INVISIBLE (8200 1225);
FORCEADD Q_CAP..1
(400 2475);
FORCEPROP 1 LAST LOCATION C2412
J 0
(450 2575);
DISPLAY 0.489362 (450 2575);
PAINT SKYBLUE (450 2575);
FORCEPROP 2 LAST $SEC 1
J 0
(450 2675);
DISPLAY 0.680851 (450 2675);
PAINT MONO (450 2675);
DISPLAY INVISIBLE (450 2675);
FORCEPROP 2 LAST CDS_SEC 1
J 0
(450 2675);
DISPLAY 1.021277 (450 2675);
DISPLAY INVISIBLE (450 2675);
FORCEPROP 1 LASTPIN (400 2575) $PN 1
J 0
(410 2555);
DISPLAY 0.489362 (410 2555);
FORCEPROP 1 LASTPIN (400 2375) $PN 2
J 0
(410 2355);
DISPLAY 0.489362 (410 2355);
FORCEPROP 1 LAST MATERIAL X6S
J 0
(450 2375);
DISPLAY 0.489362 (450 2375);
PAINT SKYBLUE (450 2375);
FORCEPROP 1 LAST TOLERANCE 20%
J 0
(450 2425);
DISPLAY 0.489362 (450 2425);
PAINT SKYBLUE (450 2425);
FORCEPROP 1 LAST VALUE 22UF
J 0
(450 2525);
DISPLAY 0.489362 (450 2525);
PAINT SKYBLUE (450 2525);
FORCEPROP 1 LAST VOLTAGE 4V
J 0
(450 2475);
DISPLAY 0.489362 (450 2475);
PAINT SKYBLUE (450 2475);
FORCEPROP 1 LAST PACK_TYPE C0402
J 0
(450 2275);
DISPLAY 0.489362 (450 2275);
PAINT SKYBLUE (450 2275);
FORCEPROP 2 LAST CDS_LIB pure_quanta
J 0
(400 2475);
PAINT MONO (400 2475);
DISPLAY INVISIBLE (400 2475);
FORCEPROP 1 LAST PATH I11
J 0
(450 2625);
DISPLAY 0.978723 (450 2625);
PAINT WHITE (450 2625);
DISPLAY INVISIBLE (450 2625);
FORCEPROP 1 LAST PART_NUMBER CH622KMEB02
J 0
(450 2325);
DISPLAY 0.489362 (450 2325);
PAINT SKYBLUE (450 2325);
DISPLAY INVISIBLE (450 2325);
FORCEADD Q_CAP..1
(6350 2025);
FORCEPROP 1 LAST LOCATION C2496
J 0
(6400 2125);
DISPLAY 0.489362 (6400 2125);
PAINT SKYBLUE (6400 2125);
FORCEPROP 2 LAST $SEC 1
J 0
(6400 2225);
DISPLAY 0.680851 (6400 2225);
PAINT MONO (6400 2225);
DISPLAY INVISIBLE (6400 2225);
FORCEPROP 2 LAST CDS_SEC 1
J 0
(6400 2225);
DISPLAY 1.021277 (6400 2225);
DISPLAY INVISIBLE (6400 2225);
FORCEPROP 1 LASTPIN (6350 2125) $PN 1
J 0
(6360 2105);
DISPLAY 0.489362 (6360 2105);
FORCEPROP 1 LASTPIN (6350 1925) $PN 2
J 0
(6360 1905);
DISPLAY 0.489362 (6360 1905);
FORCEPROP 1 LAST MATERIAL X6S
J 0
(6400 1925);
DISPLAY 0.489362 (6400 1925);
PAINT SKYBLUE (6400 1925);
FORCEPROP 1 LAST TOLERANCE 20%
J 0
(6400 1975);
DISPLAY 0.489362 (6400 1975);
PAINT SKYBLUE (6400 1975);
FORCEPROP 1 LAST VALUE 22UF
J 0
(6400 2075);
DISPLAY 0.489362 (6400 2075);
PAINT SKYBLUE (6400 2075);
FORCEPROP 1 LAST VOLTAGE 4V
J 0
(6400 2025);
DISPLAY 0.489362 (6400 2025);
PAINT SKYBLUE (6400 2025);
FORCEPROP 1 LAST PACK_TYPE C0402
J 0
(6400 1825);
DISPLAY 0.489362 (6400 1825);
PAINT SKYBLUE (6400 1825);
FORCEPROP 2 LAST CDS_LIB pure_quanta
J 0
(6350 2025);
PAINT MONO (6350 2025);
DISPLAY INVISIBLE (6350 2025);
FORCEPROP 1 LAST PATH I110
J 0
(6400 2175);
DISPLAY 0.978723 (6400 2175);
PAINT WHITE (6400 2175);
DISPLAY INVISIBLE (6400 2175);
FORCEPROP 1 LAST PART_NUMBER CH622KMEB02
J 0
(6400 1875);
DISPLAY 0.489362 (6400 1875);
PAINT SKYBLUE (6400 1875);
DISPLAY INVISIBLE (6400 1875);
FORCEADD Q_CAP..1
(6350 2650);
FORCEPROP 1 LAST LOCATION C2495
J 0
(6400 2750);
DISPLAY 0.489362 (6400 2750);
PAINT SKYBLUE (6400 2750);
FORCEPROP 2 LAST $SEC 1
J 0
(6400 2850);
DISPLAY 0.680851 (6400 2850);
PAINT MONO (6400 2850);
DISPLAY INVISIBLE (6400 2850);
FORCEPROP 2 LAST CDS_SEC 1
J 0
(6400 2850);
DISPLAY 1.021277 (6400 2850);
DISPLAY INVISIBLE (6400 2850);
FORCEPROP 1 LASTPIN (6350 2750) $PN 1
J 0
(6360 2730);
DISPLAY 0.489362 (6360 2730);
FORCEPROP 1 LASTPIN (6350 2550) $PN 2
J 0
(6360 2530);
DISPLAY 0.489362 (6360 2530);
FORCEPROP 1 LAST MATERIAL X6S
J 0
(6400 2550);
DISPLAY 0.489362 (6400 2550);
PAINT SKYBLUE (6400 2550);
FORCEPROP 1 LAST TOLERANCE 20%
J 0
(6400 2600);
DISPLAY 0.489362 (6400 2600);
PAINT SKYBLUE (6400 2600);
FORCEPROP 1 LAST VALUE 22UF
J 0
(6400 2700);
DISPLAY 0.489362 (6400 2700);
PAINT SKYBLUE (6400 2700);
FORCEPROP 1 LAST VOLTAGE 4V
J 0
(6400 2650);
DISPLAY 0.489362 (6400 2650);
PAINT SKYBLUE (6400 2650);
FORCEPROP 1 LAST PACK_TYPE C0402
J 0
(6400 2450);
DISPLAY 0.489362 (6400 2450);
PAINT SKYBLUE (6400 2450);
FORCEPROP 2 LAST CDS_LIB pure_quanta
J 0
(6350 2650);
PAINT MONO (6350 2650);
DISPLAY INVISIBLE (6350 2650);
FORCEPROP 1 LAST PATH I111
J 0
(6400 2800);
DISPLAY 0.978723 (6400 2800);
PAINT WHITE (6400 2800);
DISPLAY INVISIBLE (6400 2800);
FORCEPROP 1 LAST PART_NUMBER CH622KMEB02
J 0
(6400 2500);
DISPLAY 0.489362 (6400 2500);
PAINT SKYBLUE (6400 2500);
DISPLAY INVISIBLE (6400 2500);
FORCEADD Q_CAP..1
(6800 2025);
FORCEPROP 1 LAST LOCATION C2501
J 0
(6850 2125);
DISPLAY 0.489362 (6850 2125);
PAINT SKYBLUE (6850 2125);
FORCEPROP 2 LAST $SEC 1
J 0
(6850 2225);
DISPLAY 0.680851 (6850 2225);
PAINT MONO (6850 2225);
DISPLAY INVISIBLE (6850 2225);
FORCEPROP 2 LAST CDS_SEC 1
J 0
(6850 2225);
DISPLAY 1.021277 (6850 2225);
DISPLAY INVISIBLE (6850 2225);
FORCEPROP 1 LASTPIN (6800 2125) $PN 1
J 0
(6810 2105);
DISPLAY 0.489362 (6810 2105);
FORCEPROP 1 LASTPIN (6800 1925) $PN 2
J 0
(6810 1905);
DISPLAY 0.489362 (6810 1905);
FORCEPROP 1 LAST MATERIAL X6S
J 0
(6850 1925);
DISPLAY 0.489362 (6850 1925);
PAINT SKYBLUE (6850 1925);
FORCEPROP 1 LAST TOLERANCE 20%
J 0
(6850 1975);
DISPLAY 0.489362 (6850 1975);
PAINT SKYBLUE (6850 1975);
FORCEPROP 1 LAST VALUE 22UF
J 0
(6850 2075);
DISPLAY 0.489362 (6850 2075);
PAINT SKYBLUE (6850 2075);
FORCEPROP 1 LAST VOLTAGE 4V
J 0
(6850 2025);
DISPLAY 0.489362 (6850 2025);
PAINT SKYBLUE (6850 2025);
FORCEPROP 1 LAST PACK_TYPE C0402
J 0
(6850 1825);
DISPLAY 0.489362 (6850 1825);
PAINT SKYBLUE (6850 1825);
FORCEPROP 2 LAST CDS_LIB pure_quanta
J 0
(6800 2025);
PAINT MONO (6800 2025);
DISPLAY INVISIBLE (6800 2025);
FORCEPROP 1 LAST PATH I112
J 0
(6850 2175);
DISPLAY 0.978723 (6850 2175);
PAINT WHITE (6850 2175);
DISPLAY INVISIBLE (6850 2175);
FORCEPROP 1 LAST PART_NUMBER CH622KMEB02
J 0
(6850 1875);
DISPLAY 0.489362 (6850 1875);
PAINT SKYBLUE (6850 1875);
DISPLAY INVISIBLE (6850 1875);
FORCEADD Q_CAP..1
(6800 2650);
FORCEPROP 1 LAST LOCATION C2500
J 0
(6850 2750);
DISPLAY 0.489362 (6850 2750);
PAINT SKYBLUE (6850 2750);
FORCEPROP 2 LAST $SEC 1
J 0
(6850 2850);
DISPLAY 0.680851 (6850 2850);
PAINT MONO (6850 2850);
DISPLAY INVISIBLE (6850 2850);
FORCEPROP 2 LAST CDS_SEC 1
J 0
(6850 2850);
DISPLAY 1.021277 (6850 2850);
DISPLAY INVISIBLE (6850 2850);
FORCEPROP 1 LASTPIN (6800 2750) $PN 1
J 0
(6810 2730);
DISPLAY 0.489362 (6810 2730);
FORCEPROP 1 LASTPIN (6800 2550) $PN 2
J 0
(6810 2530);
DISPLAY 0.489362 (6810 2530);
FORCEPROP 1 LAST MATERIAL X6S
J 0
(6850 2550);
DISPLAY 0.489362 (6850 2550);
PAINT SKYBLUE (6850 2550);
FORCEPROP 1 LAST TOLERANCE 20%
J 0
(6850 2600);
DISPLAY 0.489362 (6850 2600);
PAINT SKYBLUE (6850 2600);
FORCEPROP 1 LAST VALUE 22UF
J 0
(6850 2700);
DISPLAY 0.489362 (6850 2700);
PAINT SKYBLUE (6850 2700);
FORCEPROP 1 LAST VOLTAGE 4V
J 0
(6850 2650);
DISPLAY 0.489362 (6850 2650);
PAINT SKYBLUE (6850 2650);
FORCEPROP 1 LAST PACK_TYPE C0402
J 0
(6850 2450);
DISPLAY 0.489362 (6850 2450);
PAINT SKYBLUE (6850 2450);
FORCEPROP 2 LAST CDS_LIB pure_quanta
J 0
(6800 2650);
PAINT MONO (6800 2650);
DISPLAY INVISIBLE (6800 2650);
FORCEPROP 1 LAST PATH I113
J 0
(6850 2800);
DISPLAY 0.978723 (6850 2800);
PAINT WHITE (6850 2800);
DISPLAY INVISIBLE (6850 2800);
FORCEPROP 1 LAST PART_NUMBER CH622KMEB02
J 0
(6850 2500);
DISPLAY 0.489362 (6850 2500);
PAINT SKYBLUE (6850 2500);
DISPLAY INVISIBLE (6850 2500);
FORCEADD Q_CAP..1
(6350 3325);
FORCEPROP 1 LAST LOCATION C2494
J 0
(6400 3425);
DISPLAY 0.489362 (6400 3425);
PAINT SKYBLUE (6400 3425);
FORCEPROP 2 LAST $SEC 1
J 0
(6400 3525);
DISPLAY 0.680851 (6400 3525);
PAINT MONO (6400 3525);
DISPLAY INVISIBLE (6400 3525);
FORCEPROP 2 LAST CDS_SEC 1
J 0
(6400 3525);
DISPLAY 1.021277 (6400 3525);
DISPLAY INVISIBLE (6400 3525);
FORCEPROP 1 LASTPIN (6350 3425) $PN 1
J 0
(6360 3405);
DISPLAY 0.489362 (6360 3405);
FORCEPROP 1 LASTPIN (6350 3225) $PN 2
J 0
(6360 3205);
DISPLAY 0.489362 (6360 3205);
FORCEPROP 1 LAST MATERIAL X6S
J 0
(6400 3225);
DISPLAY 0.489362 (6400 3225);
PAINT SKYBLUE (6400 3225);
FORCEPROP 1 LAST TOLERANCE 20%
J 0
(6400 3275);
DISPLAY 0.489362 (6400 3275);
PAINT SKYBLUE (6400 3275);
FORCEPROP 1 LAST VALUE 22UF
J 0
(6400 3375);
DISPLAY 0.489362 (6400 3375);
PAINT SKYBLUE (6400 3375);
FORCEPROP 1 LAST VOLTAGE 4V
J 0
(6400 3325);
DISPLAY 0.489362 (6400 3325);
PAINT SKYBLUE (6400 3325);
FORCEPROP 1 LAST PACK_TYPE C0402
J 0
(6400 3125);
DISPLAY 0.489362 (6400 3125);
PAINT SKYBLUE (6400 3125);
FORCEPROP 2 LAST CDS_LIB pure_quanta
J 0
(6350 3325);
PAINT MONO (6350 3325);
DISPLAY INVISIBLE (6350 3325);
FORCEPROP 1 LAST PATH I114
J 0
(6400 3475);
DISPLAY 0.978723 (6400 3475);
PAINT WHITE (6400 3475);
DISPLAY INVISIBLE (6400 3475);
FORCEPROP 1 LAST PART_NUMBER CH622KMEB02
J 0
(6400 3175);
DISPLAY 0.489362 (6400 3175);
PAINT SKYBLUE (6400 3175);
DISPLAY INVISIBLE (6400 3175);
FORCEADD UNIVERSAL_GND..1
(6350 3925);
FORCEPROP 3 LASTPIN (6350 3975) SIG_NAME GND\g
J 0
(6360 3985);
DISPLAY 0.659574 (6360 3985);
PAINT MONO (6360 3985);
DISPLAY INVISIBLE (6360 3985);
FORCEPROP 2 LAST CDS_LIB pure_quanta_power
J 0
(6350 3925);
DISPLAY INVISIBLE (6350 3925);
FORCEPROP 1 LAST HDL_POWER GND
J 1
(6375 3850);
DISPLAY 0.872340 (6375 3850);
PAINT GREEN (6375 3850);
DISPLAY INVISIBLE (6375 3850);
FORCEPROP 1 LAST PATH I115
J 0
(6425 3925);
DISPLAY 0.872340 (6425 3925);
PAINT AQUA (6425 3925);
DISPLAY INVISIBLE (6425 3925);
FORCEADD Q_CAP..1
(6800 3325);
FORCEPROP 1 LAST LOCATION C2499
J 0
(6850 3425);
DISPLAY 0.489362 (6850 3425);
PAINT SKYBLUE (6850 3425);
FORCEPROP 2 LAST $SEC 1
J 0
(6850 3525);
DISPLAY 0.680851 (6850 3525);
PAINT MONO (6850 3525);
DISPLAY INVISIBLE (6850 3525);
FORCEPROP 2 LAST CDS_SEC 1
J 0
(6850 3525);
DISPLAY 1.021277 (6850 3525);
DISPLAY INVISIBLE (6850 3525);
FORCEPROP 1 LASTPIN (6800 3425) $PN 1
J 0
(6810 3405);
DISPLAY 0.489362 (6810 3405);
FORCEPROP 1 LASTPIN (6800 3225) $PN 2
J 0
(6810 3205);
DISPLAY 0.489362 (6810 3205);
FORCEPROP 1 LAST MATERIAL X6S
J 0
(6850 3225);
DISPLAY 0.489362 (6850 3225);
PAINT SKYBLUE (6850 3225);
FORCEPROP 1 LAST TOLERANCE 20%
J 0
(6850 3275);
DISPLAY 0.489362 (6850 3275);
PAINT SKYBLUE (6850 3275);
FORCEPROP 1 LAST VALUE 22UF
J 0
(6850 3375);
DISPLAY 0.489362 (6850 3375);
PAINT SKYBLUE (6850 3375);
FORCEPROP 1 LAST VOLTAGE 4V
J 0
(6850 3325);
DISPLAY 0.489362 (6850 3325);
PAINT SKYBLUE (6850 3325);
FORCEPROP 1 LAST PACK_TYPE C0402
J 0
(6850 3125);
DISPLAY 0.489362 (6850 3125);
PAINT SKYBLUE (6850 3125);
FORCEPROP 2 LAST CDS_LIB pure_quanta
J 0
(6800 3325);
PAINT MONO (6800 3325);
DISPLAY INVISIBLE (6800 3325);
FORCEPROP 1 LAST PATH I116
J 0
(6850 3475);
DISPLAY 0.978723 (6850 3475);
PAINT WHITE (6850 3475);
DISPLAY INVISIBLE (6850 3475);
FORCEPROP 1 LAST PART_NUMBER CH622KMEB02
J 0
(6850 3175);
DISPLAY 0.489362 (6850 3175);
PAINT SKYBLUE (6850 3175);
DISPLAY INVISIBLE (6850 3175);
FORCEADD Q_CAP..1
(7250 2025);
FORCEPROP 1 LAST LOCATION C2505
J 0
(7300 2125);
DISPLAY 0.489362 (7300 2125);
PAINT SKYBLUE (7300 2125);
FORCEPROP 2 LAST $SEC 1
J 0
(7300 2225);
DISPLAY 0.680851 (7300 2225);
PAINT MONO (7300 2225);
DISPLAY INVISIBLE (7300 2225);
FORCEPROP 2 LAST CDS_SEC 1
J 0
(7300 2225);
DISPLAY 1.021277 (7300 2225);
DISPLAY INVISIBLE (7300 2225);
FORCEPROP 1 LASTPIN (7250 2125) $PN 1
J 0
(7260 2105);
DISPLAY 0.489362 (7260 2105);
FORCEPROP 1 LASTPIN (7250 1925) $PN 2
J 0
(7260 1905);
DISPLAY 0.489362 (7260 1905);
FORCEPROP 1 LAST MATERIAL X6S
J 0
(7300 1925);
DISPLAY 0.489362 (7300 1925);
PAINT SKYBLUE (7300 1925);
FORCEPROP 1 LAST TOLERANCE 20%
J 0
(7300 1975);
DISPLAY 0.489362 (7300 1975);
PAINT SKYBLUE (7300 1975);
FORCEPROP 1 LAST VALUE 22UF
J 0
(7300 2075);
DISPLAY 0.489362 (7300 2075);
PAINT SKYBLUE (7300 2075);
FORCEPROP 1 LAST VOLTAGE 4V
J 0
(7300 2025);
DISPLAY 0.489362 (7300 2025);
PAINT SKYBLUE (7300 2025);
FORCEPROP 1 LAST PACK_TYPE C0402
J 0
(7300 1825);
DISPLAY 0.489362 (7300 1825);
PAINT SKYBLUE (7300 1825);
FORCEPROP 2 LAST CDS_LIB pure_quanta
J 0
(7250 2025);
PAINT MONO (7250 2025);
DISPLAY INVISIBLE (7250 2025);
FORCEPROP 1 LAST PATH I117
J 0
(7300 2175);
DISPLAY 0.978723 (7300 2175);
PAINT WHITE (7300 2175);
DISPLAY INVISIBLE (7300 2175);
FORCEPROP 1 LAST PART_NUMBER CH622KMEB02
J 0
(7300 1875);
DISPLAY 0.489362 (7300 1875);
PAINT SKYBLUE (7300 1875);
DISPLAY INVISIBLE (7300 1875);
FORCEADD Q_CAP..1
(7250 2650);
FORCEPROP 1 LAST LOCATION C2504
J 0
(7300 2750);
DISPLAY 0.489362 (7300 2750);
PAINT SKYBLUE (7300 2750);
FORCEPROP 2 LAST $SEC 1
J 0
(7300 2850);
DISPLAY 0.680851 (7300 2850);
PAINT MONO (7300 2850);
DISPLAY INVISIBLE (7300 2850);
FORCEPROP 2 LAST CDS_SEC 1
J 0
(7300 2850);
DISPLAY 1.021277 (7300 2850);
DISPLAY INVISIBLE (7300 2850);
FORCEPROP 1 LASTPIN (7250 2750) $PN 1
J 0
(7260 2730);
DISPLAY 0.489362 (7260 2730);
FORCEPROP 1 LASTPIN (7250 2550) $PN 2
J 0
(7260 2530);
DISPLAY 0.489362 (7260 2530);
FORCEPROP 1 LAST MATERIAL X6S
J 0
(7300 2550);
DISPLAY 0.489362 (7300 2550);
PAINT SKYBLUE (7300 2550);
FORCEPROP 1 LAST TOLERANCE 20%
J 0
(7300 2600);
DISPLAY 0.489362 (7300 2600);
PAINT SKYBLUE (7300 2600);
FORCEPROP 1 LAST VALUE 22UF
J 0
(7300 2700);
DISPLAY 0.489362 (7300 2700);
PAINT SKYBLUE (7300 2700);
FORCEPROP 1 LAST VOLTAGE 4V
J 0
(7300 2650);
DISPLAY 0.489362 (7300 2650);
PAINT SKYBLUE (7300 2650);
FORCEPROP 1 LAST PACK_TYPE C0402
J 0
(7300 2450);
DISPLAY 0.489362 (7300 2450);
PAINT SKYBLUE (7300 2450);
FORCEPROP 2 LAST CDS_LIB pure_quanta
J 0
(7250 2650);
PAINT MONO (7250 2650);
DISPLAY INVISIBLE (7250 2650);
FORCEPROP 1 LAST PATH I118
J 0
(7300 2800);
DISPLAY 0.978723 (7300 2800);
PAINT WHITE (7300 2800);
DISPLAY INVISIBLE (7300 2800);
FORCEPROP 1 LAST PART_NUMBER CH622KMEB02
J 0
(7300 2500);
DISPLAY 0.489362 (7300 2500);
PAINT SKYBLUE (7300 2500);
DISPLAY INVISIBLE (7300 2500);
FORCEADD Q_CAP..1
(7700 2650);
FORCEPROP 1 LAST LOCATION C2113
J 0
(7750 2750);
DISPLAY 0.489362 (7750 2750);
PAINT SKYBLUE (7750 2750);
FORCEPROP 2 LAST $SEC 1
J 0
(7750 2850);
DISPLAY 0.680851 (7750 2850);
PAINT MONO (7750 2850);
DISPLAY INVISIBLE (7750 2850);
FORCEPROP 2 LAST CDS_SEC 1
J 0
(7750 2850);
DISPLAY 1.021277 (7750 2850);
DISPLAY INVISIBLE (7750 2850);
FORCEPROP 1 LASTPIN (7700 2750) $PN 1
J 0
(7710 2730);
DISPLAY 0.489362 (7710 2730);
FORCEPROP 1 LASTPIN (7700 2550) $PN 2
J 0
(7710 2530);
DISPLAY 0.489362 (7710 2530);
FORCEPROP 1 LAST MATERIAL X6S
J 0
(7750 2550);
DISPLAY 0.489362 (7750 2550);
PAINT SKYBLUE (7750 2550);
FORCEPROP 1 LAST TOLERANCE 20%
J 0
(7750 2600);
DISPLAY 0.489362 (7750 2600);
PAINT SKYBLUE (7750 2600);
FORCEPROP 1 LAST VALUE 22UF
J 0
(7750 2700);
DISPLAY 0.489362 (7750 2700);
PAINT SKYBLUE (7750 2700);
FORCEPROP 1 LAST VOLTAGE 4V
J 0
(7750 2650);
DISPLAY 0.489362 (7750 2650);
PAINT SKYBLUE (7750 2650);
FORCEPROP 1 LAST PACK_TYPE C0402
J 0
(7750 2450);
DISPLAY 0.489362 (7750 2450);
PAINT SKYBLUE (7750 2450);
FORCEPROP 2 LAST CDS_LIB pure_quanta
J 0
(7700 2650);
PAINT MONO (7700 2650);
DISPLAY INVISIBLE (7700 2650);
FORCEPROP 1 LAST PATH I119
J 0
(7750 2800);
DISPLAY 0.978723 (7750 2800);
PAINT WHITE (7750 2800);
DISPLAY INVISIBLE (7750 2800);
FORCEPROP 1 LAST PART_NUMBER CH622KMEB02
J 0
(7750 2500);
DISPLAY 0.489362 (7750 2500);
PAINT SKYBLUE (7750 2500);
DISPLAY INVISIBLE (7750 2500);
FORCEADD UNIVERSAL_POWER..1
(400 2750);
FORCEPROP 3 LASTPIN (400 2700) SIG_NAME PVDDCR_SOC_P1\g
J 0
(410 2710);
DISPLAY 0.659574 (410 2710);
PAINT MONO (410 2710);
DISPLAY INVISIBLE (410 2710);
FORCEPROP 1 LAST HDL_POWER PVDDCR_SOC_P1
J 1
(400 2800);
DISPLAY 0.489362 (400 2800);
PAINT GREEN (400 2800);
FORCEPROP 2 LAST CDS_LIB pure_quanta_power
J 0
(400 2750);
DISPLAY INVISIBLE (400 2750);
FORCEPROP 1 LAST PATH I12
J 0
(450 2775);
DISPLAY 0.872340 (450 2775);
PAINT AQUA (450 2775);
DISPLAY INVISIBLE (450 2775);
FORCEADD Q_CAP..1
(7700 2025);
FORCEPROP 1 LAST LOCATION C2114
J 0
(7750 2125);
DISPLAY 0.489362 (7750 2125);
PAINT SKYBLUE (7750 2125);
FORCEPROP 2 LAST $SEC 1
J 0
(7750 2225);
DISPLAY 0.680851 (7750 2225);
PAINT MONO (7750 2225);
DISPLAY INVISIBLE (7750 2225);
FORCEPROP 2 LAST CDS_SEC 1
J 0
(7750 2225);
DISPLAY 1.021277 (7750 2225);
DISPLAY INVISIBLE (7750 2225);
FORCEPROP 1 LASTPIN (7700 2125) $PN 1
J 0
(7710 2105);
DISPLAY 0.489362 (7710 2105);
FORCEPROP 1 LASTPIN (7700 1925) $PN 2
J 0
(7710 1905);
DISPLAY 0.489362 (7710 1905);
FORCEPROP 1 LAST MATERIAL X6S
J 0
(7750 1925);
DISPLAY 0.489362 (7750 1925);
PAINT SKYBLUE (7750 1925);
FORCEPROP 1 LAST TOLERANCE 20%
J 0
(7750 1975);
DISPLAY 0.489362 (7750 1975);
PAINT SKYBLUE (7750 1975);
FORCEPROP 1 LAST VALUE 22UF
J 0
(7750 2075);
DISPLAY 0.489362 (7750 2075);
PAINT SKYBLUE (7750 2075);
FORCEPROP 1 LAST VOLTAGE 4V
J 0
(7750 2025);
DISPLAY 0.489362 (7750 2025);
PAINT SKYBLUE (7750 2025);
FORCEPROP 1 LAST PACK_TYPE C0402
J 0
(7750 1825);
DISPLAY 0.489362 (7750 1825);
PAINT SKYBLUE (7750 1825);
FORCEPROP 2 LAST CDS_LIB pure_quanta
J 0
(7700 2025);
PAINT MONO (7700 2025);
DISPLAY INVISIBLE (7700 2025);
FORCEPROP 1 LAST PATH I120
J 0
(7750 2175);
DISPLAY 0.978723 (7750 2175);
PAINT WHITE (7750 2175);
DISPLAY INVISIBLE (7750 2175);
FORCEPROP 1 LAST PART_NUMBER CH622KMEB02
J 0
(7750 1875);
DISPLAY 0.489362 (7750 1875);
PAINT SKYBLUE (7750 1875);
DISPLAY INVISIBLE (7750 1875);
FORCEADD Q_CAP..1
(8150 2025);
FORCEPROP 1 LAST LOCATION C2120
J 0
(8200 2125);
DISPLAY 0.489362 (8200 2125);
PAINT SKYBLUE (8200 2125);
FORCEPROP 2 LAST $SEC 1
J 0
(8200 2225);
DISPLAY 0.680851 (8200 2225);
PAINT MONO (8200 2225);
DISPLAY INVISIBLE (8200 2225);
FORCEPROP 2 LAST CDS_SEC 1
J 0
(8200 2225);
DISPLAY 1.021277 (8200 2225);
DISPLAY INVISIBLE (8200 2225);
FORCEPROP 1 LASTPIN (8150 2125) $PN 1
J 0
(8160 2105);
DISPLAY 0.489362 (8160 2105);
FORCEPROP 1 LASTPIN (8150 1925) $PN 2
J 0
(8160 1905);
DISPLAY 0.489362 (8160 1905);
FORCEPROP 1 LAST MATERIAL X6S
J 0
(8200 1925);
DISPLAY 0.489362 (8200 1925);
PAINT SKYBLUE (8200 1925);
FORCEPROP 1 LAST TOLERANCE 20%
J 0
(8200 1975);
DISPLAY 0.489362 (8200 1975);
PAINT SKYBLUE (8200 1975);
FORCEPROP 1 LAST VALUE 22UF
J 0
(8200 2075);
DISPLAY 0.489362 (8200 2075);
PAINT SKYBLUE (8200 2075);
FORCEPROP 1 LAST VOLTAGE 4V
J 0
(8200 2025);
DISPLAY 0.489362 (8200 2025);
PAINT SKYBLUE (8200 2025);
FORCEPROP 1 LAST PACK_TYPE C0402
J 0
(8200 1825);
DISPLAY 0.489362 (8200 1825);
PAINT SKYBLUE (8200 1825);
FORCEPROP 2 LAST CDS_LIB pure_quanta
J 0
(8150 2025);
PAINT MONO (8150 2025);
DISPLAY INVISIBLE (8150 2025);
FORCEPROP 1 LAST PATH I121
J 0
(8200 2175);
DISPLAY 0.978723 (8200 2175);
PAINT WHITE (8200 2175);
DISPLAY INVISIBLE (8200 2175);
FORCEPROP 1 LAST PART_NUMBER CH622KMEB02
J 0
(8200 1875);
DISPLAY 0.489362 (8200 1875);
PAINT SKYBLUE (8200 1875);
DISPLAY INVISIBLE (8200 1875);
FORCEADD Q_CAP..1
(8150 2650);
FORCEPROP 1 LAST LOCATION C2119
J 0
(8200 2750);
DISPLAY 0.489362 (8200 2750);
PAINT SKYBLUE (8200 2750);
FORCEPROP 2 LAST $SEC 1
J 0
(8200 2850);
DISPLAY 0.680851 (8200 2850);
PAINT MONO (8200 2850);
DISPLAY INVISIBLE (8200 2850);
FORCEPROP 2 LAST CDS_SEC 1
J 0
(8200 2850);
DISPLAY 1.021277 (8200 2850);
DISPLAY INVISIBLE (8200 2850);
FORCEPROP 1 LASTPIN (8150 2750) $PN 1
J 0
(8160 2730);
DISPLAY 0.489362 (8160 2730);
FORCEPROP 1 LASTPIN (8150 2550) $PN 2
J 0
(8160 2530);
DISPLAY 0.489362 (8160 2530);
FORCEPROP 1 LAST MATERIAL X6S
J 0
(8200 2550);
DISPLAY 0.489362 (8200 2550);
PAINT SKYBLUE (8200 2550);
FORCEPROP 1 LAST TOLERANCE 20%
J 0
(8200 2600);
DISPLAY 0.489362 (8200 2600);
PAINT SKYBLUE (8200 2600);
FORCEPROP 1 LAST VALUE 22UF
J 0
(8200 2700);
DISPLAY 0.489362 (8200 2700);
PAINT SKYBLUE (8200 2700);
FORCEPROP 1 LAST VOLTAGE 4V
J 0
(8200 2650);
DISPLAY 0.489362 (8200 2650);
PAINT SKYBLUE (8200 2650);
FORCEPROP 1 LAST PACK_TYPE C0402
J 0
(8200 2450);
DISPLAY 0.489362 (8200 2450);
PAINT SKYBLUE (8200 2450);
FORCEPROP 2 LAST CDS_LIB pure_quanta
J 0
(8150 2650);
PAINT MONO (8150 2650);
DISPLAY INVISIBLE (8150 2650);
FORCEPROP 1 LAST PATH I122
J 0
(8200 2800);
DISPLAY 0.978723 (8200 2800);
PAINT WHITE (8200 2800);
DISPLAY INVISIBLE (8200 2800);
FORCEPROP 1 LAST PART_NUMBER CH622KMEB02
J 0
(8200 2500);
DISPLAY 0.489362 (8200 2500);
PAINT SKYBLUE (8200 2500);
DISPLAY INVISIBLE (8200 2500);
FORCEADD Q_CAP..1
(7250 3325);
FORCEPROP 1 LAST LOCATION C2503
J 0
(7300 3425);
DISPLAY 0.489362 (7300 3425);
PAINT SKYBLUE (7300 3425);
FORCEPROP 2 LAST $SEC 1
J 0
(7300 3525);
DISPLAY 0.680851 (7300 3525);
PAINT MONO (7300 3525);
DISPLAY INVISIBLE (7300 3525);
FORCEPROP 2 LAST CDS_SEC 1
J 0
(7300 3525);
DISPLAY 1.021277 (7300 3525);
DISPLAY INVISIBLE (7300 3525);
FORCEPROP 1 LASTPIN (7250 3425) $PN 1
J 0
(7260 3405);
DISPLAY 0.489362 (7260 3405);
FORCEPROP 1 LASTPIN (7250 3225) $PN 2
J 0
(7260 3205);
DISPLAY 0.489362 (7260 3205);
FORCEPROP 1 LAST MATERIAL X6S
J 0
(7300 3225);
DISPLAY 0.489362 (7300 3225);
PAINT SKYBLUE (7300 3225);
FORCEPROP 1 LAST TOLERANCE 20%
J 0
(7300 3275);
DISPLAY 0.489362 (7300 3275);
PAINT SKYBLUE (7300 3275);
FORCEPROP 1 LAST VALUE 22UF
J 0
(7300 3375);
DISPLAY 0.489362 (7300 3375);
PAINT SKYBLUE (7300 3375);
FORCEPROP 1 LAST VOLTAGE 4V
J 0
(7300 3325);
DISPLAY 0.489362 (7300 3325);
PAINT SKYBLUE (7300 3325);
FORCEPROP 1 LAST PACK_TYPE C0402
J 0
(7300 3125);
DISPLAY 0.489362 (7300 3125);
PAINT SKYBLUE (7300 3125);
FORCEPROP 2 LAST CDS_LIB pure_quanta
J 0
(7250 3325);
PAINT MONO (7250 3325);
DISPLAY INVISIBLE (7250 3325);
FORCEPROP 1 LAST PATH I123
J 0
(7300 3475);
DISPLAY 0.978723 (7300 3475);
PAINT WHITE (7300 3475);
DISPLAY INVISIBLE (7300 3475);
FORCEPROP 1 LAST PART_NUMBER CH622KMEB02
J 0
(7300 3175);
DISPLAY 0.489362 (7300 3175);
PAINT SKYBLUE (7300 3175);
DISPLAY INVISIBLE (7300 3175);
FORCEADD Q_CAP..1
(7700 3325);
FORCEPROP 1 LAST LOCATION C2508
J 0
(7750 3425);
DISPLAY 0.489362 (7750 3425);
PAINT SKYBLUE (7750 3425);
FORCEPROP 2 LAST $SEC 1
J 0
(7750 3525);
DISPLAY 0.680851 (7750 3525);
PAINT MONO (7750 3525);
DISPLAY INVISIBLE (7750 3525);
FORCEPROP 2 LAST CDS_SEC 1
J 0
(7750 3525);
DISPLAY 1.021277 (7750 3525);
DISPLAY INVISIBLE (7750 3525);
FORCEPROP 1 LASTPIN (7700 3425) $PN 1
J 0
(7710 3405);
DISPLAY 0.489362 (7710 3405);
FORCEPROP 1 LASTPIN (7700 3225) $PN 2
J 0
(7710 3205);
DISPLAY 0.489362 (7710 3205);
FORCEPROP 1 LAST MATERIAL X6S
J 0
(7750 3225);
DISPLAY 0.489362 (7750 3225);
PAINT SKYBLUE (7750 3225);
FORCEPROP 1 LAST TOLERANCE 20%
J 0
(7750 3275);
DISPLAY 0.489362 (7750 3275);
PAINT SKYBLUE (7750 3275);
FORCEPROP 1 LAST VALUE 22UF
J 0
(7750 3375);
DISPLAY 0.489362 (7750 3375);
PAINT SKYBLUE (7750 3375);
FORCEPROP 1 LAST VOLTAGE 4V
J 0
(7750 3325);
DISPLAY 0.489362 (7750 3325);
PAINT SKYBLUE (7750 3325);
FORCEPROP 1 LAST PACK_TYPE C0402
J 0
(7750 3125);
DISPLAY 0.489362 (7750 3125);
PAINT SKYBLUE (7750 3125);
FORCEPROP 2 LAST CDS_LIB pure_quanta
J 0
(7700 3325);
PAINT MONO (7700 3325);
DISPLAY INVISIBLE (7700 3325);
FORCEPROP 1 LAST PATH I124
J 0
(7750 3475);
DISPLAY 0.978723 (7750 3475);
PAINT WHITE (7750 3475);
DISPLAY INVISIBLE (7750 3475);
FORCEPROP 1 LAST PART_NUMBER CH622KMEB02
J 0
(7750 3175);
DISPLAY 0.489362 (7750 3175);
PAINT SKYBLUE (7750 3175);
DISPLAY INVISIBLE (7750 3175);
FORCEADD Q_CAP..1
(8150 3325);
FORCEPROP 1 LAST LOCATION C2118
J 0
(8200 3425);
DISPLAY 0.489362 (8200 3425);
PAINT SKYBLUE (8200 3425);
FORCEPROP 2 LAST $SEC 1
J 0
(8200 3525);
DISPLAY 0.680851 (8200 3525);
PAINT MONO (8200 3525);
DISPLAY INVISIBLE (8200 3525);
FORCEPROP 2 LAST CDS_SEC 1
J 0
(8200 3525);
DISPLAY 1.021277 (8200 3525);
DISPLAY INVISIBLE (8200 3525);
FORCEPROP 1 LASTPIN (8150 3425) $PN 1
J 0
(8160 3405);
DISPLAY 0.489362 (8160 3405);
FORCEPROP 1 LASTPIN (8150 3225) $PN 2
J 0
(8160 3205);
DISPLAY 0.489362 (8160 3205);
FORCEPROP 1 LAST MATERIAL X6S
J 0
(8200 3225);
DISPLAY 0.489362 (8200 3225);
PAINT SKYBLUE (8200 3225);
FORCEPROP 1 LAST TOLERANCE 20%
J 0
(8200 3275);
DISPLAY 0.489362 (8200 3275);
PAINT SKYBLUE (8200 3275);
FORCEPROP 1 LAST VALUE 22UF
J 0
(8200 3375);
DISPLAY 0.489362 (8200 3375);
PAINT SKYBLUE (8200 3375);
FORCEPROP 1 LAST VOLTAGE 4V
J 0
(8200 3325);
DISPLAY 0.489362 (8200 3325);
PAINT SKYBLUE (8200 3325);
FORCEPROP 1 LAST PACK_TYPE C0402
J 0
(8200 3125);
DISPLAY 0.489362 (8200 3125);
PAINT SKYBLUE (8200 3125);
FORCEPROP 2 LAST CDS_LIB pure_quanta
J 0
(8150 3325);
PAINT MONO (8150 3325);
DISPLAY INVISIBLE (8150 3325);
FORCEPROP 1 LAST PATH I125
J 0
(8200 3475);
DISPLAY 0.978723 (8200 3475);
PAINT WHITE (8200 3475);
DISPLAY INVISIBLE (8200 3475);
FORCEPROP 1 LAST PART_NUMBER CH622KMEB02
J 0
(8200 3175);
DISPLAY 0.489362 (8200 3175);
PAINT SKYBLUE (8200 3175);
DISPLAY INVISIBLE (8200 3175);
FORCEADD UNIVERSAL_GND..1
(4400 4175);
FORCEPROP 3 LASTPIN (4400 4225) SIG_NAME GND\g
J 0
(4410 4235);
DISPLAY 0.659574 (4410 4235);
PAINT MONO (4410 4235);
DISPLAY INVISIBLE (4410 4235);
FORCEPROP 2 LAST CDS_LIB pure_quanta_power
J 0
(4400 4175);
PAINT MONO (4400 4175);
DISPLAY INVISIBLE (4400 4175);
FORCEPROP 1 LAST HDL_POWER GND
J 1
(4425 4100);
DISPLAY 0.872340 (4425 4100);
PAINT GREEN (4425 4100);
DISPLAY INVISIBLE (4425 4100);
FORCEPROP 1 LAST PATH I126
J 0
(4475 4175);
DISPLAY 0.872340 (4475 4175);
PAINT AQUA (4475 4175);
DISPLAY INVISIBLE (4475 4175);
FORCEADD Q_CAP..1
(4400 4550);
FORCEPROP 1 LAST LOCATION C2472
J 0
(4450 4650);
DISPLAY 0.489362 (4450 4650);
PAINT SKYBLUE (4450 4650);
FORCEPROP 2 LAST $SEC 1
J 0
(4450 4750);
DISPLAY 0.680851 (4450 4750);
PAINT MONO (4450 4750);
DISPLAY INVISIBLE (4450 4750);
FORCEPROP 2 LAST CDS_SEC 1
J 0
(4450 4750);
DISPLAY 1.021277 (4450 4750);
DISPLAY INVISIBLE (4450 4750);
FORCEPROP 1 LASTPIN (4400 4650) $PN 1
J 0
(4410 4630);
DISPLAY 0.489362 (4410 4630);
FORCEPROP 1 LASTPIN (4400 4450) $PN 2
J 0
(4410 4430);
DISPLAY 0.489362 (4410 4430);
FORCEPROP 1 LAST MATERIAL X6S
J 0
(4450 4450);
DISPLAY 0.489362 (4450 4450);
PAINT SKYBLUE (4450 4450);
FORCEPROP 1 LAST TOLERANCE 20%
J 0
(4450 4500);
DISPLAY 0.489362 (4450 4500);
PAINT SKYBLUE (4450 4500);
FORCEPROP 1 LAST VALUE 22UF
J 0
(4450 4600);
DISPLAY 0.489362 (4450 4600);
PAINT SKYBLUE (4450 4600);
FORCEPROP 1 LAST VOLTAGE 4V
J 0
(4450 4550);
DISPLAY 0.489362 (4450 4550);
PAINT SKYBLUE (4450 4550);
FORCEPROP 1 LAST PACK_TYPE C0402
J 0
(4450 4350);
DISPLAY 0.489362 (4450 4350);
PAINT SKYBLUE (4450 4350);
FORCEPROP 2 LAST CDS_LIB pure_quanta
J 0
(4400 4550);
PAINT MONO (4400 4550);
DISPLAY INVISIBLE (4400 4550);
FORCEPROP 1 LAST PATH I127
J 0
(4450 4700);
DISPLAY 0.978723 (4450 4700);
PAINT WHITE (4450 4700);
DISPLAY INVISIBLE (4450 4700);
FORCEPROP 1 LAST PART_NUMBER CH622KMEB02
J 0
(4450 4400);
DISPLAY 0.489362 (4450 4400);
PAINT SKYBLUE (4450 4400);
DISPLAY INVISIBLE (4450 4400);
FORCEADD UNIVERSAL_GND..1
(4400 4850);
FORCEPROP 3 LASTPIN (4400 4900) SIG_NAME GND\g
J 0
(4410 4910);
DISPLAY 0.659574 (4410 4910);
PAINT MONO (4410 4910);
DISPLAY INVISIBLE (4410 4910);
FORCEPROP 2 LAST CDS_LIB pure_quanta_power
J 0
(4400 4850);
PAINT MONO (4400 4850);
DISPLAY INVISIBLE (4400 4850);
FORCEPROP 1 LAST HDL_POWER GND
J 1
(4425 4775);
DISPLAY 0.872340 (4425 4775);
PAINT GREEN (4425 4775);
DISPLAY INVISIBLE (4425 4775);
FORCEPROP 1 LAST PATH I128
J 0
(4475 4850);
DISPLAY 0.872340 (4475 4850);
PAINT AQUA (4475 4850);
DISPLAY INVISIBLE (4475 4850);
FORCEADD Q_CAP..1
(5000 4300);
FORCEPROP 1 LAST LOCATION C2479
J 0
(5050 4400);
DISPLAY 0.489362 (5050 4400);
PAINT SKYBLUE (5050 4400);
FORCEPROP 2 LAST $SEC 1
J 0
(5050 4500);
DISPLAY 0.680851 (5050 4500);
PAINT MONO (5050 4500);
DISPLAY INVISIBLE (5050 4500);
FORCEPROP 2 LAST CDS_SEC 1
J 0
(5050 4500);
DISPLAY 1.021277 (5050 4500);
DISPLAY INVISIBLE (5050 4500);
FORCEPROP 1 LASTPIN (5000 4400) $PN 1
J 0
(5010 4380);
DISPLAY 0.489362 (5010 4380);
FORCEPROP 1 LASTPIN (5000 4200) $PN 2
J 0
(5010 4180);
DISPLAY 0.489362 (5010 4180);
FORCEPROP 1 LAST MATERIAL X6S
J 0
(5050 4200);
DISPLAY 0.489362 (5050 4200);
PAINT SKYBLUE (5050 4200);
FORCEPROP 1 LAST TOLERANCE 20%
J 0
(5050 4250);
DISPLAY 0.489362 (5050 4250);
PAINT SKYBLUE (5050 4250);
FORCEPROP 1 LAST VALUE 22UF
J 0
(5050 4350);
DISPLAY 0.489362 (5050 4350);
PAINT SKYBLUE (5050 4350);
FORCEPROP 1 LAST VOLTAGE 4V
J 0
(5050 4300);
DISPLAY 0.489362 (5050 4300);
PAINT SKYBLUE (5050 4300);
FORCEPROP 1 LAST PACK_TYPE C0402
J 0
(5050 4100);
DISPLAY 0.489362 (5050 4100);
PAINT SKYBLUE (5050 4100);
FORCEPROP 2 LAST CDS_LIB pure_quanta
J 0
(5000 4300);
PAINT MONO (5000 4300);
DISPLAY INVISIBLE (5000 4300);
FORCEPROP 1 LAST PATH I129
J 0
(5050 4450);
DISPLAY 0.978723 (5050 4450);
PAINT WHITE (5050 4450);
DISPLAY INVISIBLE (5050 4450);
FORCEPROP 1 LAST PART_NUMBER CH622KMEB02
J 0
(5050 4150);
DISPLAY 0.489362 (5050 4150);
PAINT SKYBLUE (5050 4150);
DISPLAY INVISIBLE (5050 4150);
FORCEADD Q_CAP..1
(850 2475);
FORCEPROP 1 LAST LOCATION C2419
J 0
(900 2575);
DISPLAY 0.489362 (900 2575);
PAINT SKYBLUE (900 2575);
FORCEPROP 2 LAST $SEC 1
J 0
(900 2675);
DISPLAY 0.680851 (900 2675);
PAINT MONO (900 2675);
DISPLAY INVISIBLE (900 2675);
FORCEPROP 2 LAST CDS_SEC 1
J 0
(900 2675);
DISPLAY 1.021277 (900 2675);
DISPLAY INVISIBLE (900 2675);
FORCEPROP 1 LASTPIN (850 2575) $PN 1
J 0
(860 2555);
DISPLAY 0.489362 (860 2555);
FORCEPROP 1 LASTPIN (850 2375) $PN 2
J 0
(860 2355);
DISPLAY 0.489362 (860 2355);
FORCEPROP 1 LAST MATERIAL X6S
J 0
(900 2375);
DISPLAY 0.489362 (900 2375);
PAINT SKYBLUE (900 2375);
FORCEPROP 1 LAST TOLERANCE 20%
J 0
(900 2425);
DISPLAY 0.489362 (900 2425);
PAINT SKYBLUE (900 2425);
FORCEPROP 1 LAST VALUE 22UF
J 0
(900 2525);
DISPLAY 0.489362 (900 2525);
PAINT SKYBLUE (900 2525);
FORCEPROP 1 LAST VOLTAGE 4V
J 0
(900 2475);
DISPLAY 0.489362 (900 2475);
PAINT SKYBLUE (900 2475);
FORCEPROP 1 LAST PACK_TYPE C0402
J 0
(900 2275);
DISPLAY 0.489362 (900 2275);
PAINT SKYBLUE (900 2275);
FORCEPROP 2 LAST CDS_LIB pure_quanta
J 0
(850 2475);
PAINT MONO (850 2475);
DISPLAY INVISIBLE (850 2475);
FORCEPROP 1 LAST PATH I13
J 0
(900 2625);
DISPLAY 0.978723 (900 2625);
PAINT WHITE (900 2625);
DISPLAY INVISIBLE (900 2625);
FORCEPROP 1 LAST PART_NUMBER CH622KMEB02
J 0
(900 2325);
DISPLAY 0.489362 (900 2325);
PAINT SKYBLUE (900 2325);
DISPLAY INVISIBLE (900 2325);
FORCEADD UNIVERSAL_POWER..1
(5000 4575);
FORCEPROP 3 LASTPIN (5000 4525) SIG_NAME PVDDIO_P1\g
J 0
(5010 4535);
DISPLAY 0.659574 (5010 4535);
PAINT MONO (5010 4535);
DISPLAY INVISIBLE (5010 4535);
FORCEPROP 1 LAST HDL_POWER PVDDIO_P1
J 1
(5000 4625);
DISPLAY 0.489362 (5000 4625);
PAINT GREEN (5000 4625);
FORCEPROP 2 LAST CDS_LIB pure_quanta_power
J 0
(5000 4575);
DISPLAY INVISIBLE (5000 4575);
FORCEPROP 1 LAST PATH I130
J 0
(5050 4600);
DISPLAY 0.872340 (5050 4600);
PAINT AQUA (5050 4600);
DISPLAY INVISIBLE (5050 4600);
FORCEADD Q_CAP..1
(4400 5225);
FORCEPROP 1 LAST LOCATION C2471
J 0
(4450 5325);
DISPLAY 0.489362 (4450 5325);
PAINT SKYBLUE (4450 5325);
FORCEPROP 2 LAST $SEC 1
J 0
(4450 5425);
DISPLAY 0.680851 (4450 5425);
PAINT MONO (4450 5425);
DISPLAY INVISIBLE (4450 5425);
FORCEPROP 2 LAST CDS_SEC 1
J 0
(4450 5425);
DISPLAY 1.021277 (4450 5425);
DISPLAY INVISIBLE (4450 5425);
FORCEPROP 1 LASTPIN (4400 5325) $PN 1
J 0
(4410 5305);
DISPLAY 0.489362 (4410 5305);
FORCEPROP 1 LASTPIN (4400 5125) $PN 2
J 0
(4410 5105);
DISPLAY 0.489362 (4410 5105);
FORCEPROP 1 LAST MATERIAL X6S
J 0
(4450 5125);
DISPLAY 0.489362 (4450 5125);
PAINT SKYBLUE (4450 5125);
FORCEPROP 1 LAST TOLERANCE 20%
J 0
(4450 5175);
DISPLAY 0.489362 (4450 5175);
PAINT SKYBLUE (4450 5175);
FORCEPROP 1 LAST VALUE 22UF
J 0
(4450 5275);
DISPLAY 0.489362 (4450 5275);
PAINT SKYBLUE (4450 5275);
FORCEPROP 1 LAST VOLTAGE 4V
J 0
(4450 5225);
DISPLAY 0.489362 (4450 5225);
PAINT SKYBLUE (4450 5225);
FORCEPROP 1 LAST PACK_TYPE C0402
J 0
(4450 5025);
DISPLAY 0.489362 (4450 5025);
PAINT SKYBLUE (4450 5025);
FORCEPROP 2 LAST CDS_LIB pure_quanta
J 0
(4400 5225);
PAINT MONO (4400 5225);
DISPLAY INVISIBLE (4400 5225);
FORCEPROP 1 LAST PATH I131
J 0
(4450 5375);
DISPLAY 0.978723 (4450 5375);
PAINT WHITE (4450 5375);
DISPLAY INVISIBLE (4450 5375);
FORCEPROP 1 LAST PART_NUMBER CH622KMEB02
J 0
(4450 5075);
DISPLAY 0.489362 (4450 5075);
PAINT SKYBLUE (4450 5075);
DISPLAY INVISIBLE (4450 5075);
FORCEADD UNIVERSAL_GND..1
(4400 5500);
FORCEPROP 3 LASTPIN (4400 5550) SIG_NAME GND\g
J 0
(4410 5560);
DISPLAY 0.659574 (4410 5560);
PAINT MONO (4410 5560);
DISPLAY INVISIBLE (4410 5560);
FORCEPROP 2 LAST CDS_LIB pure_quanta_power
J 0
(4400 5500);
PAINT MONO (4400 5500);
DISPLAY INVISIBLE (4400 5500);
FORCEPROP 1 LAST HDL_POWER GND
J 1
(4425 5425);
DISPLAY 0.872340 (4425 5425);
PAINT GREEN (4425 5425);
DISPLAY INVISIBLE (4425 5425);
FORCEPROP 1 LAST PATH I132
J 0
(4475 5500);
DISPLAY 0.872340 (4475 5500);
PAINT AQUA (4475 5500);
DISPLAY INVISIBLE (4475 5500);
FORCEADD Q_CAP..1
(4400 5875);
FORCEPROP 1 LAST LOCATION C2470
J 0
(4450 5975);
DISPLAY 0.489362 (4450 5975);
PAINT SKYBLUE (4450 5975);
FORCEPROP 2 LAST $SEC 1
J 0
(4450 6075);
DISPLAY 0.680851 (4450 6075);
PAINT MONO (4450 6075);
DISPLAY INVISIBLE (4450 6075);
FORCEPROP 2 LAST CDS_SEC 1
J 0
(4450 6075);
DISPLAY 1.021277 (4450 6075);
DISPLAY INVISIBLE (4450 6075);
FORCEPROP 1 LASTPIN (4400 5975) $PN 1
J 0
(4410 5955);
DISPLAY 0.489362 (4410 5955);
FORCEPROP 1 LASTPIN (4400 5775) $PN 2
J 0
(4410 5755);
DISPLAY 0.489362 (4410 5755);
FORCEPROP 1 LAST MATERIAL X6S
J 0
(4450 5775);
DISPLAY 0.489362 (4450 5775);
PAINT SKYBLUE (4450 5775);
FORCEPROP 1 LAST TOLERANCE 20%
J 0
(4450 5825);
DISPLAY 0.489362 (4450 5825);
PAINT SKYBLUE (4450 5825);
FORCEPROP 1 LAST VALUE 22UF
J 0
(4450 5925);
DISPLAY 0.489362 (4450 5925);
PAINT SKYBLUE (4450 5925);
FORCEPROP 1 LAST VOLTAGE 4V
J 0
(4450 5875);
DISPLAY 0.489362 (4450 5875);
PAINT SKYBLUE (4450 5875);
FORCEPROP 1 LAST PACK_TYPE C0402
J 0
(4450 5675);
DISPLAY 0.489362 (4450 5675);
PAINT SKYBLUE (4450 5675);
FORCEPROP 2 LAST CDS_LIB pure_quanta
J 0
(4400 5875);
PAINT MONO (4400 5875);
DISPLAY INVISIBLE (4400 5875);
FORCEPROP 1 LAST PATH I133
J 0
(4450 6025);
DISPLAY 0.978723 (4450 6025);
PAINT WHITE (4450 6025);
DISPLAY INVISIBLE (4450 6025);
FORCEPROP 1 LAST PART_NUMBER CH622KMEB02
J 0
(4450 5725);
DISPLAY 0.489362 (4450 5725);
PAINT SKYBLUE (4450 5725);
DISPLAY INVISIBLE (4450 5725);
FORCEADD Q_CAP..1
(4975 5075);
FORCEPROP 1 LAST LOCATION C2478
J 0
(5025 5175);
DISPLAY 0.489362 (5025 5175);
PAINT SKYBLUE (5025 5175);
FORCEPROP 2 LAST $SEC 1
J 0
(5025 5275);
DISPLAY 0.680851 (5025 5275);
PAINT MONO (5025 5275);
DISPLAY INVISIBLE (5025 5275);
FORCEPROP 2 LAST CDS_SEC 1
J 0
(5025 5275);
DISPLAY 1.021277 (5025 5275);
DISPLAY INVISIBLE (5025 5275);
FORCEPROP 1 LASTPIN (4975 5175) $PN 1
J 0
(4985 5155);
DISPLAY 0.489362 (4985 5155);
FORCEPROP 1 LASTPIN (4975 4975) $PN 2
J 0
(4985 4955);
DISPLAY 0.489362 (4985 4955);
FORCEPROP 1 LAST MATERIAL X6S
J 0
(5025 4975);
DISPLAY 0.489362 (5025 4975);
PAINT SKYBLUE (5025 4975);
FORCEPROP 1 LAST TOLERANCE 20%
J 0
(5025 5025);
DISPLAY 0.489362 (5025 5025);
PAINT SKYBLUE (5025 5025);
FORCEPROP 1 LAST VALUE 22UF
J 0
(5025 5125);
DISPLAY 0.489362 (5025 5125);
PAINT SKYBLUE (5025 5125);
FORCEPROP 1 LAST VOLTAGE 4V
J 0
(5025 5075);
DISPLAY 0.489362 (5025 5075);
PAINT SKYBLUE (5025 5075);
FORCEPROP 1 LAST PACK_TYPE C0402
J 0
(5025 4875);
DISPLAY 0.489362 (5025 4875);
PAINT SKYBLUE (5025 4875);
FORCEPROP 2 LAST CDS_LIB pure_quanta
J 0
(4975 5075);
PAINT MONO (4975 5075);
DISPLAY INVISIBLE (4975 5075);
FORCEPROP 1 LAST PATH I134
J 0
(5025 5225);
DISPLAY 0.978723 (5025 5225);
PAINT WHITE (5025 5225);
DISPLAY INVISIBLE (5025 5225);
FORCEPROP 1 LAST PART_NUMBER CH622KMEB02
J 0
(5025 4925);
DISPLAY 0.489362 (5025 4925);
PAINT SKYBLUE (5025 4925);
DISPLAY INVISIBLE (5025 4925);
FORCEADD UNIVERSAL_POWER..1
(4975 5350);
FORCEPROP 3 LASTPIN (4975 5300) SIG_NAME PVDDIO_P1\g
J 0
(4985 5310);
DISPLAY 0.659574 (4985 5310);
PAINT MONO (4985 5310);
DISPLAY INVISIBLE (4985 5310);
FORCEPROP 1 LAST HDL_POWER PVDDIO_P1
J 1
(4975 5400);
DISPLAY 0.489362 (4975 5400);
PAINT GREEN (4975 5400);
FORCEPROP 2 LAST CDS_LIB pure_quanta_power
J 0
(4975 5350);
DISPLAY INVISIBLE (4975 5350);
FORCEPROP 1 LAST PATH I135
J 0
(5025 5375);
DISPLAY 0.872340 (5025 5375);
PAINT AQUA (5025 5375);
DISPLAY INVISIBLE (5025 5375);
FORCEADD Q_CAP..1
(4975 5875);
FORCEPROP 1 LAST LOCATION C2477
J 0
(5025 5975);
DISPLAY 0.489362 (5025 5975);
PAINT SKYBLUE (5025 5975);
FORCEPROP 2 LAST $SEC 1
J 0
(5025 6075);
DISPLAY 0.680851 (5025 6075);
PAINT MONO (5025 6075);
DISPLAY INVISIBLE (5025 6075);
FORCEPROP 2 LAST CDS_SEC 1
J 0
(5025 6075);
DISPLAY 1.021277 (5025 6075);
DISPLAY INVISIBLE (5025 6075);
FORCEPROP 1 LASTPIN (4975 5975) $PN 1
J 0
(4985 5955);
DISPLAY 0.489362 (4985 5955);
FORCEPROP 1 LASTPIN (4975 5775) $PN 2
J 0
(4985 5755);
DISPLAY 0.489362 (4985 5755);
FORCEPROP 1 LAST MATERIAL X6S
J 0
(5025 5775);
DISPLAY 0.489362 (5025 5775);
PAINT SKYBLUE (5025 5775);
FORCEPROP 1 LAST TOLERANCE 20%
J 0
(5025 5825);
DISPLAY 0.489362 (5025 5825);
PAINT SKYBLUE (5025 5825);
FORCEPROP 1 LAST VALUE 22UF
J 0
(5025 5925);
DISPLAY 0.489362 (5025 5925);
PAINT SKYBLUE (5025 5925);
FORCEPROP 1 LAST VOLTAGE 4V
J 0
(5025 5875);
DISPLAY 0.489362 (5025 5875);
PAINT SKYBLUE (5025 5875);
FORCEPROP 1 LAST PACK_TYPE C0402
J 0
(5025 5675);
DISPLAY 0.489362 (5025 5675);
PAINT SKYBLUE (5025 5675);
FORCEPROP 2 LAST CDS_LIB pure_quanta
J 0
(4975 5875);
PAINT MONO (4975 5875);
DISPLAY INVISIBLE (4975 5875);
FORCEPROP 1 LAST PATH I136
J 0
(5025 6025);
DISPLAY 0.978723 (5025 6025);
PAINT WHITE (5025 6025);
DISPLAY INVISIBLE (5025 6025);
FORCEPROP 1 LAST PART_NUMBER CH622KMEB02
J 0
(5025 5725);
DISPLAY 0.489362 (5025 5725);
PAINT SKYBLUE (5025 5725);
DISPLAY INVISIBLE (5025 5725);
FORCEADD Q_CAP..1
(5450 4300);
FORCEPROP 1 LAST LOCATION C2103
J 0
(5500 4400);
DISPLAY 0.489362 (5500 4400);
PAINT SKYBLUE (5500 4400);
FORCEPROP 2 LAST $SEC 1
J 0
(5500 4500);
DISPLAY 0.680851 (5500 4500);
PAINT MONO (5500 4500);
DISPLAY INVISIBLE (5500 4500);
FORCEPROP 2 LAST CDS_SEC 1
J 0
(5500 4500);
DISPLAY 1.021277 (5500 4500);
DISPLAY INVISIBLE (5500 4500);
FORCEPROP 1 LASTPIN (5450 4400) $PN 1
J 0
(5460 4380);
DISPLAY 0.489362 (5460 4380);
FORCEPROP 1 LASTPIN (5450 4200) $PN 2
J 0
(5460 4180);
DISPLAY 0.489362 (5460 4180);
FORCEPROP 1 LAST MATERIAL X6S
J 0
(5500 4200);
DISPLAY 0.489362 (5500 4200);
PAINT SKYBLUE (5500 4200);
FORCEPROP 1 LAST TOLERANCE 20%
J 0
(5500 4250);
DISPLAY 0.489362 (5500 4250);
PAINT SKYBLUE (5500 4250);
FORCEPROP 1 LAST VALUE 22UF
J 0
(5500 4350);
DISPLAY 0.489362 (5500 4350);
PAINT SKYBLUE (5500 4350);
FORCEPROP 1 LAST VOLTAGE 4V
J 0
(5500 4300);
DISPLAY 0.489362 (5500 4300);
PAINT SKYBLUE (5500 4300);
FORCEPROP 1 LAST PACK_TYPE C0402
J 0
(5500 4100);
DISPLAY 0.489362 (5500 4100);
PAINT SKYBLUE (5500 4100);
FORCEPROP 2 LAST CDS_LIB pure_quanta
J 0
(5450 4300);
PAINT MONO (5450 4300);
DISPLAY INVISIBLE (5450 4300);
FORCEPROP 1 LAST PATH I137
J 0
(5500 4450);
DISPLAY 0.978723 (5500 4450);
PAINT WHITE (5500 4450);
DISPLAY INVISIBLE (5500 4450);
FORCEPROP 1 LAST PART_NUMBER CH622KMEB02
J 0
(5500 4150);
DISPLAY 0.489362 (5500 4150);
PAINT SKYBLUE (5500 4150);
DISPLAY INVISIBLE (5500 4150);
FORCEADD Q_CAP..1
(5900 4300);
FORCEPROP 1 LAST LOCATION C2106
J 0
(5950 4400);
DISPLAY 0.489362 (5950 4400);
PAINT SKYBLUE (5950 4400);
FORCEPROP 2 LAST $SEC 1
J 0
(5950 4500);
DISPLAY 0.680851 (5950 4500);
PAINT MONO (5950 4500);
DISPLAY INVISIBLE (5950 4500);
FORCEPROP 2 LAST CDS_SEC 1
J 0
(5950 4500);
DISPLAY 1.021277 (5950 4500);
DISPLAY INVISIBLE (5950 4500);
FORCEPROP 1 LASTPIN (5900 4400) $PN 1
J 0
(5910 4380);
DISPLAY 0.489362 (5910 4380);
FORCEPROP 1 LASTPIN (5900 4200) $PN 2
J 0
(5910 4180);
DISPLAY 0.489362 (5910 4180);
FORCEPROP 1 LAST MATERIAL X6S
J 0
(5950 4200);
DISPLAY 0.489362 (5950 4200);
PAINT SKYBLUE (5950 4200);
FORCEPROP 1 LAST TOLERANCE 20%
J 0
(5950 4250);
DISPLAY 0.489362 (5950 4250);
PAINT SKYBLUE (5950 4250);
FORCEPROP 1 LAST VALUE 22UF
J 0
(5950 4350);
DISPLAY 0.489362 (5950 4350);
PAINT SKYBLUE (5950 4350);
FORCEPROP 1 LAST VOLTAGE 4V
J 0
(5950 4300);
DISPLAY 0.489362 (5950 4300);
PAINT SKYBLUE (5950 4300);
FORCEPROP 1 LAST PACK_TYPE C0402
J 0
(5950 4100);
DISPLAY 0.489362 (5950 4100);
PAINT SKYBLUE (5950 4100);
FORCEPROP 2 LAST CDS_LIB pure_quanta
J 0
(5900 4300);
PAINT MONO (5900 4300);
DISPLAY INVISIBLE (5900 4300);
FORCEPROP 1 LAST PATH I138
J 0
(5950 4450);
DISPLAY 0.978723 (5950 4450);
PAINT WHITE (5950 4450);
DISPLAY INVISIBLE (5950 4450);
FORCEPROP 1 LAST PART_NUMBER CH622KMEB02
J 0
(5950 4150);
DISPLAY 0.489362 (5950 4150);
PAINT SKYBLUE (5950 4150);
DISPLAY INVISIBLE (5950 4150);
FORCEADD Q_CAP..1
(5425 5075);
FORCEPROP 1 LAST LOCATION C2484
J 0
(5475 5175);
DISPLAY 0.489362 (5475 5175);
PAINT SKYBLUE (5475 5175);
FORCEPROP 2 LAST $SEC 1
J 0
(5475 5275);
DISPLAY 0.680851 (5475 5275);
PAINT MONO (5475 5275);
DISPLAY INVISIBLE (5475 5275);
FORCEPROP 2 LAST CDS_SEC 1
J 0
(5475 5275);
DISPLAY 1.021277 (5475 5275);
DISPLAY INVISIBLE (5475 5275);
FORCEPROP 1 LASTPIN (5425 5175) $PN 1
J 0
(5435 5155);
DISPLAY 0.489362 (5435 5155);
FORCEPROP 1 LASTPIN (5425 4975) $PN 2
J 0
(5435 4955);
DISPLAY 0.489362 (5435 4955);
FORCEPROP 1 LAST MATERIAL X6S
J 0
(5475 4975);
DISPLAY 0.489362 (5475 4975);
PAINT SKYBLUE (5475 4975);
FORCEPROP 1 LAST TOLERANCE 20%
J 0
(5475 5025);
DISPLAY 0.489362 (5475 5025);
PAINT SKYBLUE (5475 5025);
FORCEPROP 1 LAST VALUE 22UF
J 0
(5475 5125);
DISPLAY 0.489362 (5475 5125);
PAINT SKYBLUE (5475 5125);
FORCEPROP 1 LAST VOLTAGE 4V
J 0
(5475 5075);
DISPLAY 0.489362 (5475 5075);
PAINT SKYBLUE (5475 5075);
FORCEPROP 1 LAST PACK_TYPE C0402
J 0
(5475 4875);
DISPLAY 0.489362 (5475 4875);
PAINT SKYBLUE (5475 4875);
FORCEPROP 2 LAST CDS_LIB pure_quanta
J 0
(5425 5075);
PAINT MONO (5425 5075);
DISPLAY INVISIBLE (5425 5075);
FORCEPROP 1 LAST PATH I139
J 0
(5475 5225);
DISPLAY 0.978723 (5475 5225);
PAINT WHITE (5475 5225);
DISPLAY INVISIBLE (5475 5225);
FORCEPROP 1 LAST PART_NUMBER CH622KMEB02
J 0
(5475 4925);
DISPLAY 0.489362 (5475 4925);
PAINT SKYBLUE (5475 4925);
DISPLAY INVISIBLE (5475 4925);
FORCEADD Q_CAP..1
(400 3150);
FORCEPROP 1 LAST LOCATION C2411
J 0
(450 3250);
DISPLAY 0.489362 (450 3250);
PAINT SKYBLUE (450 3250);
FORCEPROP 2 LAST $SEC 1
J 0
(450 3350);
DISPLAY 0.680851 (450 3350);
PAINT MONO (450 3350);
DISPLAY INVISIBLE (450 3350);
FORCEPROP 2 LAST CDS_SEC 1
J 0
(450 3350);
DISPLAY 1.021277 (450 3350);
DISPLAY INVISIBLE (450 3350);
FORCEPROP 1 LASTPIN (400 3250) $PN 1
J 0
(410 3230);
DISPLAY 0.489362 (410 3230);
FORCEPROP 1 LASTPIN (400 3050) $PN 2
J 0
(410 3030);
DISPLAY 0.489362 (410 3030);
FORCEPROP 1 LAST MATERIAL X6S
J 0
(450 3050);
DISPLAY 0.489362 (450 3050);
PAINT SKYBLUE (450 3050);
FORCEPROP 1 LAST TOLERANCE 20%
J 0
(450 3100);
DISPLAY 0.489362 (450 3100);
PAINT SKYBLUE (450 3100);
FORCEPROP 1 LAST VALUE 22UF
J 0
(450 3200);
DISPLAY 0.489362 (450 3200);
PAINT SKYBLUE (450 3200);
FORCEPROP 1 LAST VOLTAGE 4V
J 0
(450 3150);
DISPLAY 0.489362 (450 3150);
PAINT SKYBLUE (450 3150);
FORCEPROP 1 LAST PACK_TYPE C0402
J 0
(450 2950);
DISPLAY 0.489362 (450 2950);
PAINT SKYBLUE (450 2950);
FORCEPROP 2 LAST CDS_LIB pure_quanta
J 0
(400 3150);
PAINT MONO (400 3150);
DISPLAY INVISIBLE (400 3150);
FORCEPROP 1 LAST PATH I14
J 0
(450 3300);
DISPLAY 0.978723 (450 3300);
PAINT WHITE (450 3300);
DISPLAY INVISIBLE (450 3300);
FORCEPROP 1 LAST PART_NUMBER CH622KMEB02
J 0
(450 3000);
DISPLAY 0.489362 (450 3000);
PAINT SKYBLUE (450 3000);
DISPLAY INVISIBLE (450 3000);
FORCEADD Q_CAP..1
(5425 5875);
FORCEPROP 1 LAST LOCATION C2102
J 0
(5475 5975);
DISPLAY 0.489362 (5475 5975);
PAINT SKYBLUE (5475 5975);
FORCEPROP 2 LAST $SEC 1
J 0
(5475 6075);
DISPLAY 0.680851 (5475 6075);
PAINT MONO (5475 6075);
DISPLAY INVISIBLE (5475 6075);
FORCEPROP 2 LAST CDS_SEC 1
J 0
(5475 6075);
DISPLAY 1.021277 (5475 6075);
DISPLAY INVISIBLE (5475 6075);
FORCEPROP 1 LASTPIN (5425 5975) $PN 1
J 0
(5435 5955);
DISPLAY 0.489362 (5435 5955);
FORCEPROP 1 LASTPIN (5425 5775) $PN 2
J 0
(5435 5755);
DISPLAY 0.489362 (5435 5755);
FORCEPROP 1 LAST MATERIAL X6S
J 0
(5475 5775);
DISPLAY 0.489362 (5475 5775);
PAINT SKYBLUE (5475 5775);
FORCEPROP 1 LAST TOLERANCE 20%
J 0
(5475 5825);
DISPLAY 0.489362 (5475 5825);
PAINT SKYBLUE (5475 5825);
FORCEPROP 1 LAST VALUE 22UF
J 0
(5475 5925);
DISPLAY 0.489362 (5475 5925);
PAINT SKYBLUE (5475 5925);
FORCEPROP 1 LAST VOLTAGE 4V
J 0
(5475 5875);
DISPLAY 0.489362 (5475 5875);
PAINT SKYBLUE (5475 5875);
FORCEPROP 1 LAST PACK_TYPE C0402
J 0
(5475 5675);
DISPLAY 0.489362 (5475 5675);
PAINT SKYBLUE (5475 5675);
FORCEPROP 2 LAST CDS_LIB pure_quanta
J 0
(5425 5875);
PAINT MONO (5425 5875);
DISPLAY INVISIBLE (5425 5875);
FORCEPROP 1 LAST PATH I140
J 0
(5475 6025);
DISPLAY 0.978723 (5475 6025);
PAINT WHITE (5475 6025);
DISPLAY INVISIBLE (5475 6025);
FORCEPROP 1 LAST PART_NUMBER CH622KMEB02
J 0
(5475 5725);
DISPLAY 0.489362 (5475 5725);
PAINT SKYBLUE (5475 5725);
DISPLAY INVISIBLE (5475 5725);
FORCEADD Q_CAP..1
(5875 5075);
FORCEPROP 1 LAST LOCATION C2105
J 0
(5925 5175);
DISPLAY 0.489362 (5925 5175);
PAINT SKYBLUE (5925 5175);
FORCEPROP 2 LAST $SEC 1
J 0
(5925 5275);
DISPLAY 0.680851 (5925 5275);
PAINT MONO (5925 5275);
DISPLAY INVISIBLE (5925 5275);
FORCEPROP 2 LAST CDS_SEC 1
J 0
(5925 5275);
DISPLAY 1.021277 (5925 5275);
DISPLAY INVISIBLE (5925 5275);
FORCEPROP 1 LASTPIN (5875 5175) $PN 1
J 0
(5885 5155);
DISPLAY 0.489362 (5885 5155);
FORCEPROP 1 LASTPIN (5875 4975) $PN 2
J 0
(5885 4955);
DISPLAY 0.489362 (5885 4955);
FORCEPROP 1 LAST MATERIAL X6S
J 0
(5925 4975);
DISPLAY 0.489362 (5925 4975);
PAINT SKYBLUE (5925 4975);
FORCEPROP 1 LAST TOLERANCE 20%
J 0
(5925 5025);
DISPLAY 0.489362 (5925 5025);
PAINT SKYBLUE (5925 5025);
FORCEPROP 1 LAST VALUE 22UF
J 0
(5925 5125);
DISPLAY 0.489362 (5925 5125);
PAINT SKYBLUE (5925 5125);
FORCEPROP 1 LAST VOLTAGE 4V
J 0
(5925 5075);
DISPLAY 0.489362 (5925 5075);
PAINT SKYBLUE (5925 5075);
FORCEPROP 1 LAST PACK_TYPE C0402
J 0
(5925 4875);
DISPLAY 0.489362 (5925 4875);
PAINT SKYBLUE (5925 4875);
FORCEPROP 2 LAST CDS_LIB pure_quanta
J 0
(5875 5075);
PAINT MONO (5875 5075);
DISPLAY INVISIBLE (5875 5075);
FORCEPROP 1 LAST PATH I141
J 0
(5925 5225);
DISPLAY 0.978723 (5925 5225);
PAINT WHITE (5925 5225);
DISPLAY INVISIBLE (5925 5225);
FORCEPROP 1 LAST PART_NUMBER CH622KMEB02
J 0
(5925 4925);
DISPLAY 0.489362 (5925 4925);
PAINT SKYBLUE (5925 4925);
DISPLAY INVISIBLE (5925 4925);
FORCEADD Q_CAP..1
(5875 5875);
FORCEPROP 1 LAST LOCATION C2104
J 0
(5925 5975);
DISPLAY 0.489362 (5925 5975);
PAINT SKYBLUE (5925 5975);
FORCEPROP 2 LAST $SEC 1
J 0
(5925 6075);
DISPLAY 0.680851 (5925 6075);
PAINT MONO (5925 6075);
DISPLAY INVISIBLE (5925 6075);
FORCEPROP 2 LAST CDS_SEC 1
J 0
(5925 6075);
DISPLAY 1.021277 (5925 6075);
DISPLAY INVISIBLE (5925 6075);
FORCEPROP 1 LASTPIN (5875 5975) $PN 1
J 0
(5885 5955);
DISPLAY 0.489362 (5885 5955);
FORCEPROP 1 LASTPIN (5875 5775) $PN 2
J 0
(5885 5755);
DISPLAY 0.489362 (5885 5755);
FORCEPROP 1 LAST MATERIAL X6S
J 0
(5925 5775);
DISPLAY 0.489362 (5925 5775);
PAINT SKYBLUE (5925 5775);
FORCEPROP 1 LAST TOLERANCE 20%
J 0
(5925 5825);
DISPLAY 0.489362 (5925 5825);
PAINT SKYBLUE (5925 5825);
FORCEPROP 1 LAST VALUE 22UF
J 0
(5925 5925);
DISPLAY 0.489362 (5925 5925);
PAINT SKYBLUE (5925 5925);
FORCEPROP 1 LAST VOLTAGE 4V
J 0
(5925 5875);
DISPLAY 0.489362 (5925 5875);
PAINT SKYBLUE (5925 5875);
FORCEPROP 1 LAST PACK_TYPE C0402
J 0
(5925 5675);
DISPLAY 0.489362 (5925 5675);
PAINT SKYBLUE (5925 5675);
FORCEPROP 2 LAST CDS_LIB pure_quanta
J 0
(5875 5875);
PAINT MONO (5875 5875);
DISPLAY INVISIBLE (5875 5875);
FORCEPROP 1 LAST PATH I142
J 0
(5925 6025);
DISPLAY 0.978723 (5925 6025);
PAINT WHITE (5925 6025);
DISPLAY INVISIBLE (5925 6025);
FORCEPROP 1 LAST PART_NUMBER CH622KMEB02
J 0
(5925 5725);
DISPLAY 0.489362 (5925 5725);
PAINT SKYBLUE (5925 5725);
DISPLAY INVISIBLE (5925 5725);
FORCEADD UNIVERSAL_POWER..1
(4975 6150);
FORCEPROP 3 LASTPIN (4975 6100) SIG_NAME PVDDIO_P1\g
J 0
(4985 6110);
DISPLAY 0.659574 (4985 6110);
PAINT MONO (4985 6110);
DISPLAY INVISIBLE (4985 6110);
FORCEPROP 1 LAST HDL_POWER PVDDIO_P1
J 1
(4975 6200);
DISPLAY 0.489362 (4975 6200);
PAINT GREEN (4975 6200);
FORCEPROP 2 LAST CDS_LIB pure_quanta_power
J 0
(4975 6150);
DISPLAY INVISIBLE (4975 6150);
FORCEPROP 1 LAST PATH I143
J 0
(5025 6175);
DISPLAY 0.872340 (5025 6175);
PAINT AQUA (5025 6175);
DISPLAY INVISIBLE (5025 6175);
FORCEADD Q_CAP..1
(6350 4300);
FORCEPROP 1 LAST LOCATION C2108
J 0
(6400 4400);
DISPLAY 0.489362 (6400 4400);
PAINT SKYBLUE (6400 4400);
FORCEPROP 2 LAST $SEC 1
J 0
(6400 4500);
DISPLAY 0.680851 (6400 4500);
PAINT MONO (6400 4500);
DISPLAY INVISIBLE (6400 4500);
FORCEPROP 2 LAST CDS_SEC 1
J 0
(6400 4500);
DISPLAY 1.021277 (6400 4500);
DISPLAY INVISIBLE (6400 4500);
FORCEPROP 1 LASTPIN (6350 4400) $PN 1
J 0
(6360 4380);
DISPLAY 0.489362 (6360 4380);
FORCEPROP 1 LASTPIN (6350 4200) $PN 2
J 0
(6360 4180);
DISPLAY 0.489362 (6360 4180);
FORCEPROP 1 LAST MATERIAL X6S
J 0
(6400 4200);
DISPLAY 0.489362 (6400 4200);
PAINT SKYBLUE (6400 4200);
FORCEPROP 1 LAST TOLERANCE 20%
J 0
(6400 4250);
DISPLAY 0.489362 (6400 4250);
PAINT SKYBLUE (6400 4250);
FORCEPROP 1 LAST VALUE 22UF
J 0
(6400 4350);
DISPLAY 0.489362 (6400 4350);
PAINT SKYBLUE (6400 4350);
FORCEPROP 1 LAST VOLTAGE 4V
J 0
(6400 4300);
DISPLAY 0.489362 (6400 4300);
PAINT SKYBLUE (6400 4300);
FORCEPROP 1 LAST PACK_TYPE C0402
J 0
(6400 4100);
DISPLAY 0.489362 (6400 4100);
PAINT SKYBLUE (6400 4100);
FORCEPROP 2 LAST CDS_LIB pure_quanta
J 0
(6350 4300);
PAINT MONO (6350 4300);
DISPLAY INVISIBLE (6350 4300);
FORCEPROP 1 LAST PATH I144
J 0
(6400 4450);
DISPLAY 0.978723 (6400 4450);
PAINT WHITE (6400 4450);
DISPLAY INVISIBLE (6400 4450);
FORCEPROP 1 LAST PART_NUMBER CH622KMEB02
J 0
(6400 4150);
DISPLAY 0.489362 (6400 4150);
PAINT SKYBLUE (6400 4150);
DISPLAY INVISIBLE (6400 4150);
FORCEADD Q_CAP..1
(6325 5075);
FORCEPROP 1 LAST LOCATION C2107
J 0
(6375 5175);
DISPLAY 0.489362 (6375 5175);
PAINT SKYBLUE (6375 5175);
FORCEPROP 2 LAST $SEC 1
J 0
(6375 5275);
DISPLAY 0.680851 (6375 5275);
PAINT MONO (6375 5275);
DISPLAY INVISIBLE (6375 5275);
FORCEPROP 2 LAST CDS_SEC 1
J 0
(6375 5275);
DISPLAY 1.021277 (6375 5275);
DISPLAY INVISIBLE (6375 5275);
FORCEPROP 1 LASTPIN (6325 5175) $PN 1
J 0
(6335 5155);
DISPLAY 0.489362 (6335 5155);
FORCEPROP 1 LASTPIN (6325 4975) $PN 2
J 0
(6335 4955);
DISPLAY 0.489362 (6335 4955);
FORCEPROP 1 LAST MATERIAL X6S
J 0
(6375 4975);
DISPLAY 0.489362 (6375 4975);
PAINT SKYBLUE (6375 4975);
FORCEPROP 1 LAST TOLERANCE 20%
J 0
(6375 5025);
DISPLAY 0.489362 (6375 5025);
PAINT SKYBLUE (6375 5025);
FORCEPROP 1 LAST VALUE 22UF
J 0
(6375 5125);
DISPLAY 0.489362 (6375 5125);
PAINT SKYBLUE (6375 5125);
FORCEPROP 1 LAST VOLTAGE 4V
J 0
(6375 5075);
DISPLAY 0.489362 (6375 5075);
PAINT SKYBLUE (6375 5075);
FORCEPROP 1 LAST PACK_TYPE C0402
J 0
(6375 4875);
DISPLAY 0.489362 (6375 4875);
PAINT SKYBLUE (6375 4875);
FORCEPROP 2 LAST CDS_LIB pure_quanta
J 0
(6325 5075);
PAINT MONO (6325 5075);
DISPLAY INVISIBLE (6325 5075);
FORCEPROP 1 LAST PATH I145
J 0
(6375 5225);
DISPLAY 0.978723 (6375 5225);
PAINT WHITE (6375 5225);
DISPLAY INVISIBLE (6375 5225);
FORCEPROP 1 LAST PART_NUMBER CH622KMEB02
J 0
(6375 4925);
DISPLAY 0.489362 (6375 4925);
PAINT SKYBLUE (6375 4925);
DISPLAY INVISIBLE (6375 4925);
FORCEADD Q_CAP..1
(6325 5875);
FORCEPROP 1 LAST LOCATION C2493
J 0
(6375 5975);
DISPLAY 0.489362 (6375 5975);
PAINT SKYBLUE (6375 5975);
FORCEPROP 2 LAST $SEC 1
J 0
(6375 6075);
DISPLAY 0.680851 (6375 6075);
PAINT MONO (6375 6075);
DISPLAY INVISIBLE (6375 6075);
FORCEPROP 2 LAST CDS_SEC 1
J 0
(6375 6075);
DISPLAY 1.021277 (6375 6075);
DISPLAY INVISIBLE (6375 6075);
FORCEPROP 1 LASTPIN (6325 5975) $PN 1
J 0
(6335 5955);
DISPLAY 0.489362 (6335 5955);
FORCEPROP 1 LASTPIN (6325 5775) $PN 2
J 0
(6335 5755);
DISPLAY 0.489362 (6335 5755);
FORCEPROP 1 LAST MATERIAL X6S
J 0
(6375 5775);
DISPLAY 0.489362 (6375 5775);
PAINT SKYBLUE (6375 5775);
FORCEPROP 1 LAST TOLERANCE 20%
J 0
(6375 5825);
DISPLAY 0.489362 (6375 5825);
PAINT SKYBLUE (6375 5825);
FORCEPROP 1 LAST VALUE 22UF
J 0
(6375 5925);
DISPLAY 0.489362 (6375 5925);
PAINT SKYBLUE (6375 5925);
FORCEPROP 1 LAST VOLTAGE 4V
J 0
(6375 5875);
DISPLAY 0.489362 (6375 5875);
PAINT SKYBLUE (6375 5875);
FORCEPROP 1 LAST PACK_TYPE C0402
J 0
(6375 5675);
DISPLAY 0.489362 (6375 5675);
PAINT SKYBLUE (6375 5675);
FORCEPROP 2 LAST CDS_LIB pure_quanta
J 0
(6325 5875);
PAINT MONO (6325 5875);
DISPLAY INVISIBLE (6325 5875);
FORCEPROP 1 LAST PATH I146
J 0
(6375 6025);
DISPLAY 0.978723 (6375 6025);
PAINT WHITE (6375 6025);
DISPLAY INVISIBLE (6375 6025);
FORCEPROP 1 LAST PART_NUMBER CH622KMEB02
J 0
(6375 5725);
DISPLAY 0.489362 (6375 5725);
PAINT SKYBLUE (6375 5725);
DISPLAY INVISIBLE (6375 5725);
FORCEADD Q_CAP..1
(6775 5075);
FORCEPROP 1 LAST LOCATION C2498
J 0
(6825 5175);
DISPLAY 0.489362 (6825 5175);
PAINT SKYBLUE (6825 5175);
FORCEPROP 2 LAST $SEC 1
J 0
(6825 5275);
DISPLAY 0.680851 (6825 5275);
PAINT MONO (6825 5275);
DISPLAY INVISIBLE (6825 5275);
FORCEPROP 2 LAST CDS_SEC 1
J 0
(6825 5275);
DISPLAY 1.021277 (6825 5275);
DISPLAY INVISIBLE (6825 5275);
FORCEPROP 1 LASTPIN (6775 5175) $PN 1
J 0
(6785 5155);
DISPLAY 0.489362 (6785 5155);
FORCEPROP 1 LASTPIN (6775 4975) $PN 2
J 0
(6785 4955);
DISPLAY 0.489362 (6785 4955);
FORCEPROP 1 LAST MATERIAL X6S
J 0
(6825 4975);
DISPLAY 0.489362 (6825 4975);
PAINT SKYBLUE (6825 4975);
FORCEPROP 1 LAST TOLERANCE 20%
J 0
(6825 5025);
DISPLAY 0.489362 (6825 5025);
PAINT SKYBLUE (6825 5025);
FORCEPROP 1 LAST VALUE 22UF
J 0
(6825 5125);
DISPLAY 0.489362 (6825 5125);
PAINT SKYBLUE (6825 5125);
FORCEPROP 1 LAST VOLTAGE 4V
J 0
(6825 5075);
DISPLAY 0.489362 (6825 5075);
PAINT SKYBLUE (6825 5075);
FORCEPROP 1 LAST PACK_TYPE C0402
J 0
(6825 4875);
DISPLAY 0.489362 (6825 4875);
PAINT SKYBLUE (6825 4875);
FORCEPROP 2 LAST CDS_LIB pure_quanta
J 0
(6775 5075);
PAINT MONO (6775 5075);
DISPLAY INVISIBLE (6775 5075);
FORCEPROP 1 LAST PATH I147
J 0
(6825 5225);
DISPLAY 0.978723 (6825 5225);
PAINT WHITE (6825 5225);
DISPLAY INVISIBLE (6825 5225);
FORCEPROP 1 LAST PART_NUMBER CH622KMEB02
J 0
(6825 4925);
DISPLAY 0.489362 (6825 4925);
PAINT SKYBLUE (6825 4925);
DISPLAY INVISIBLE (6825 4925);
FORCEADD Q_CAP..1
(6775 5875);
FORCEPROP 1 LAST LOCATION C2109
J 0
(6825 5975);
DISPLAY 0.489362 (6825 5975);
PAINT SKYBLUE (6825 5975);
FORCEPROP 2 LAST $SEC 1
J 0
(6825 6075);
DISPLAY 0.680851 (6825 6075);
PAINT MONO (6825 6075);
DISPLAY INVISIBLE (6825 6075);
FORCEPROP 2 LAST CDS_SEC 1
J 0
(6825 6075);
DISPLAY 1.021277 (6825 6075);
DISPLAY INVISIBLE (6825 6075);
FORCEPROP 1 LASTPIN (6775 5975) $PN 1
J 0
(6785 5955);
DISPLAY 0.489362 (6785 5955);
FORCEPROP 1 LASTPIN (6775 5775) $PN 2
J 0
(6785 5755);
DISPLAY 0.489362 (6785 5755);
FORCEPROP 1 LAST MATERIAL X6S
J 0
(6825 5775);
DISPLAY 0.489362 (6825 5775);
PAINT SKYBLUE (6825 5775);
FORCEPROP 1 LAST TOLERANCE 20%
J 0
(6825 5825);
DISPLAY 0.489362 (6825 5825);
PAINT SKYBLUE (6825 5825);
FORCEPROP 1 LAST VALUE 22UF
J 0
(6825 5925);
DISPLAY 0.489362 (6825 5925);
PAINT SKYBLUE (6825 5925);
FORCEPROP 1 LAST VOLTAGE 4V
J 0
(6825 5875);
DISPLAY 0.489362 (6825 5875);
PAINT SKYBLUE (6825 5875);
FORCEPROP 1 LAST PACK_TYPE C0402
J 0
(6825 5675);
DISPLAY 0.489362 (6825 5675);
PAINT SKYBLUE (6825 5675);
FORCEPROP 2 LAST CDS_LIB pure_quanta
J 0
(6775 5875);
PAINT MONO (6775 5875);
DISPLAY INVISIBLE (6775 5875);
FORCEPROP 1 LAST PATH I148
J 0
(6825 6025);
DISPLAY 0.978723 (6825 6025);
PAINT WHITE (6825 6025);
DISPLAY INVISIBLE (6825 6025);
FORCEPROP 1 LAST PART_NUMBER CH622KMEB02
J 0
(6825 5725);
DISPLAY 0.489362 (6825 5725);
PAINT SKYBLUE (6825 5725);
DISPLAY INVISIBLE (6825 5725);
FORCEADD Q_CAP..1
(7225 5075);
FORCEPROP 1 LAST LOCATION C2111
J 0
(7275 5175);
DISPLAY 0.489362 (7275 5175);
PAINT SKYBLUE (7275 5175);
FORCEPROP 2 LAST $SEC 1
J 0
(7275 5275);
DISPLAY 0.680851 (7275 5275);
PAINT MONO (7275 5275);
DISPLAY INVISIBLE (7275 5275);
FORCEPROP 2 LAST CDS_SEC 1
J 0
(7275 5275);
DISPLAY 1.021277 (7275 5275);
DISPLAY INVISIBLE (7275 5275);
FORCEPROP 1 LASTPIN (7225 5175) $PN 1
J 0
(7235 5155);
DISPLAY 0.489362 (7235 5155);
FORCEPROP 1 LASTPIN (7225 4975) $PN 2
J 0
(7235 4955);
DISPLAY 0.489362 (7235 4955);
FORCEPROP 1 LAST MATERIAL X6S
J 0
(7275 4975);
DISPLAY 0.489362 (7275 4975);
PAINT SKYBLUE (7275 4975);
FORCEPROP 1 LAST TOLERANCE 20%
J 0
(7275 5025);
DISPLAY 0.489362 (7275 5025);
PAINT SKYBLUE (7275 5025);
FORCEPROP 1 LAST VALUE 22UF
J 0
(7275 5125);
DISPLAY 0.489362 (7275 5125);
PAINT SKYBLUE (7275 5125);
FORCEPROP 1 LAST VOLTAGE 4V
J 0
(7275 5075);
DISPLAY 0.489362 (7275 5075);
PAINT SKYBLUE (7275 5075);
FORCEPROP 1 LAST PACK_TYPE C0402
J 0
(7275 4875);
DISPLAY 0.489362 (7275 4875);
PAINT SKYBLUE (7275 4875);
FORCEPROP 2 LAST CDS_LIB pure_quanta
J 0
(7225 5075);
PAINT MONO (7225 5075);
DISPLAY INVISIBLE (7225 5075);
FORCEPROP 1 LAST PATH I149
J 0
(7275 5225);
DISPLAY 0.978723 (7275 5225);
PAINT WHITE (7275 5225);
DISPLAY INVISIBLE (7275 5225);
FORCEPROP 1 LAST PART_NUMBER CH622KMEB02
J 0
(7275 4925);
DISPLAY 0.489362 (7275 4925);
PAINT SKYBLUE (7275 4925);
DISPLAY INVISIBLE (7275 4925);
FORCEADD UNIVERSAL_POWER..1
(400 3425);
FORCEPROP 3 LASTPIN (400 3375) SIG_NAME PVDDCR_SOC_P1\g
J 0
(410 3385);
DISPLAY 0.659574 (410 3385);
PAINT MONO (410 3385);
DISPLAY INVISIBLE (410 3385);
FORCEPROP 1 LAST HDL_POWER PVDDCR_SOC_P1
J 1
(400 3475);
DISPLAY 0.489362 (400 3475);
PAINT GREEN (400 3475);
FORCEPROP 2 LAST CDS_LIB pure_quanta_power
J 0
(400 3425);
DISPLAY INVISIBLE (400 3425);
FORCEPROP 1 LAST PATH I15
J 0
(450 3450);
DISPLAY 0.872340 (450 3450);
PAINT AQUA (450 3450);
DISPLAY INVISIBLE (450 3450);
FORCEADD Q_CAP..1
(7675 5075);
FORCEPROP 1 LAST LOCATION C2112
J 0
(7725 5175);
DISPLAY 0.489362 (7725 5175);
PAINT SKYBLUE (7725 5175);
FORCEPROP 2 LAST $SEC 1
J 0
(7725 5275);
DISPLAY 0.680851 (7725 5275);
PAINT MONO (7725 5275);
DISPLAY INVISIBLE (7725 5275);
FORCEPROP 2 LAST CDS_SEC 1
J 0
(7725 5275);
DISPLAY 1.021277 (7725 5275);
DISPLAY INVISIBLE (7725 5275);
FORCEPROP 1 LASTPIN (7675 5175) $PN 1
J 0
(7685 5155);
DISPLAY 0.489362 (7685 5155);
FORCEPROP 1 LASTPIN (7675 4975) $PN 2
J 0
(7685 4955);
DISPLAY 0.489362 (7685 4955);
FORCEPROP 1 LAST MATERIAL X6S
J 0
(7725 4975);
DISPLAY 0.489362 (7725 4975);
PAINT SKYBLUE (7725 4975);
FORCEPROP 1 LAST TOLERANCE 20%
J 0
(7725 5025);
DISPLAY 0.489362 (7725 5025);
PAINT SKYBLUE (7725 5025);
FORCEPROP 1 LAST VALUE 22UF
J 0
(7725 5125);
DISPLAY 0.489362 (7725 5125);
PAINT SKYBLUE (7725 5125);
FORCEPROP 1 LAST VOLTAGE 4V
J 0
(7725 5075);
DISPLAY 0.489362 (7725 5075);
PAINT SKYBLUE (7725 5075);
FORCEPROP 1 LAST PACK_TYPE C0402
J 0
(7725 4875);
DISPLAY 0.489362 (7725 4875);
PAINT SKYBLUE (7725 4875);
FORCEPROP 2 LAST CDS_LIB pure_quanta
J 0
(7675 5075);
PAINT MONO (7675 5075);
DISPLAY INVISIBLE (7675 5075);
FORCEPROP 1 LAST PATH I150
J 0
(7725 5225);
DISPLAY 0.978723 (7725 5225);
PAINT WHITE (7725 5225);
DISPLAY INVISIBLE (7725 5225);
FORCEPROP 1 LAST PART_NUMBER CH622KMEB02
J 0
(7725 4925);
DISPLAY 0.489362 (7725 4925);
PAINT SKYBLUE (7725 4925);
DISPLAY INVISIBLE (7725 4925);
FORCEADD Q_CAP..1
(7225 5875);
FORCEPROP 1 LAST LOCATION C2110
J 0
(7275 5975);
DISPLAY 0.489362 (7275 5975);
PAINT SKYBLUE (7275 5975);
FORCEPROP 2 LAST $SEC 1
J 0
(7275 6075);
DISPLAY 0.680851 (7275 6075);
PAINT MONO (7275 6075);
DISPLAY INVISIBLE (7275 6075);
FORCEPROP 2 LAST CDS_SEC 1
J 0
(7275 6075);
DISPLAY 1.021277 (7275 6075);
DISPLAY INVISIBLE (7275 6075);
FORCEPROP 1 LASTPIN (7225 5975) $PN 1
J 0
(7235 5955);
DISPLAY 0.489362 (7235 5955);
FORCEPROP 1 LASTPIN (7225 5775) $PN 2
J 0
(7235 5755);
DISPLAY 0.489362 (7235 5755);
FORCEPROP 1 LAST MATERIAL X6S
J 0
(7275 5775);
DISPLAY 0.489362 (7275 5775);
PAINT SKYBLUE (7275 5775);
FORCEPROP 1 LAST TOLERANCE 20%
J 0
(7275 5825);
DISPLAY 0.489362 (7275 5825);
PAINT SKYBLUE (7275 5825);
FORCEPROP 1 LAST VALUE 22UF
J 0
(7275 5925);
DISPLAY 0.489362 (7275 5925);
PAINT SKYBLUE (7275 5925);
FORCEPROP 1 LAST VOLTAGE 4V
J 0
(7275 5875);
DISPLAY 0.489362 (7275 5875);
PAINT SKYBLUE (7275 5875);
FORCEPROP 1 LAST PACK_TYPE C0402
J 0
(7275 5675);
DISPLAY 0.489362 (7275 5675);
PAINT SKYBLUE (7275 5675);
FORCEPROP 2 LAST CDS_LIB pure_quanta
J 0
(7225 5875);
PAINT MONO (7225 5875);
DISPLAY INVISIBLE (7225 5875);
FORCEPROP 1 LAST PATH I151
J 0
(7275 6025);
DISPLAY 0.978723 (7275 6025);
PAINT WHITE (7275 6025);
DISPLAY INVISIBLE (7275 6025);
FORCEPROP 1 LAST PART_NUMBER CH622KMEB02
J 0
(7275 5725);
DISPLAY 0.489362 (7275 5725);
PAINT SKYBLUE (7275 5725);
DISPLAY INVISIBLE (7275 5725);
FORCEADD Q_CAP..1
(7675 5875);
FORCEPROP 1 LAST LOCATION C2507
J 0
(7725 5975);
DISPLAY 0.489362 (7725 5975);
PAINT SKYBLUE (7725 5975);
FORCEPROP 2 LAST $SEC 1
J 0
(7725 6075);
DISPLAY 0.680851 (7725 6075);
PAINT MONO (7725 6075);
DISPLAY INVISIBLE (7725 6075);
FORCEPROP 2 LAST CDS_SEC 1
J 0
(7725 6075);
DISPLAY 1.021277 (7725 6075);
DISPLAY INVISIBLE (7725 6075);
FORCEPROP 1 LASTPIN (7675 5975) $PN 1
J 0
(7685 5955);
DISPLAY 0.489362 (7685 5955);
FORCEPROP 1 LASTPIN (7675 5775) $PN 2
J 0
(7685 5755);
DISPLAY 0.489362 (7685 5755);
FORCEPROP 1 LAST MATERIAL X6S
J 0
(7725 5775);
DISPLAY 0.489362 (7725 5775);
PAINT SKYBLUE (7725 5775);
FORCEPROP 1 LAST TOLERANCE 20%
J 0
(7725 5825);
DISPLAY 0.489362 (7725 5825);
PAINT SKYBLUE (7725 5825);
FORCEPROP 1 LAST VALUE 22UF
J 0
(7725 5925);
DISPLAY 0.489362 (7725 5925);
PAINT SKYBLUE (7725 5925);
FORCEPROP 1 LAST VOLTAGE 4V
J 0
(7725 5875);
DISPLAY 0.489362 (7725 5875);
PAINT SKYBLUE (7725 5875);
FORCEPROP 1 LAST PACK_TYPE C0402
J 0
(7725 5675);
DISPLAY 0.489362 (7725 5675);
PAINT SKYBLUE (7725 5675);
FORCEPROP 2 LAST CDS_LIB pure_quanta
J 0
(7675 5875);
PAINT MONO (7675 5875);
DISPLAY INVISIBLE (7675 5875);
FORCEPROP 1 LAST PATH I152
J 0
(7725 6025);
DISPLAY 0.978723 (7725 6025);
PAINT WHITE (7725 6025);
DISPLAY INVISIBLE (7725 6025);
FORCEPROP 1 LAST PART_NUMBER CH622KMEB02
J 0
(7725 5725);
DISPLAY 0.489362 (7725 5725);
PAINT SKYBLUE (7725 5725);
DISPLAY INVISIBLE (7725 5725);
FORCEADD Q_CAP..1
(8125 5075);
FORCEPROP 1 LAST LOCATION C2117
J 0
(8175 5175);
DISPLAY 0.489362 (8175 5175);
PAINT SKYBLUE (8175 5175);
FORCEPROP 2 LAST $SEC 1
J 0
(8175 5275);
DISPLAY 0.680851 (8175 5275);
PAINT MONO (8175 5275);
DISPLAY INVISIBLE (8175 5275);
FORCEPROP 2 LAST CDS_SEC 1
J 0
(8175 5275);
DISPLAY 1.021277 (8175 5275);
DISPLAY INVISIBLE (8175 5275);
FORCEPROP 1 LASTPIN (8125 5175) $PN 1
J 0
(8135 5155);
DISPLAY 0.489362 (8135 5155);
FORCEPROP 1 LASTPIN (8125 4975) $PN 2
J 0
(8135 4955);
DISPLAY 0.489362 (8135 4955);
FORCEPROP 1 LAST MATERIAL X6S
J 0
(8175 4975);
DISPLAY 0.489362 (8175 4975);
PAINT SKYBLUE (8175 4975);
FORCEPROP 1 LAST TOLERANCE 20%
J 0
(8175 5025);
DISPLAY 0.489362 (8175 5025);
PAINT SKYBLUE (8175 5025);
FORCEPROP 1 LAST VALUE 22UF
J 0
(8175 5125);
DISPLAY 0.489362 (8175 5125);
PAINT SKYBLUE (8175 5125);
FORCEPROP 1 LAST VOLTAGE 4V
J 0
(8175 5075);
DISPLAY 0.489362 (8175 5075);
PAINT SKYBLUE (8175 5075);
FORCEPROP 1 LAST PACK_TYPE C0402
J 0
(8175 4875);
DISPLAY 0.489362 (8175 4875);
PAINT SKYBLUE (8175 4875);
FORCEPROP 2 LAST CDS_LIB pure_quanta
J 0
(8125 5075);
PAINT MONO (8125 5075);
DISPLAY INVISIBLE (8125 5075);
FORCEPROP 1 LAST PATH I153
J 0
(8175 5225);
DISPLAY 0.978723 (8175 5225);
PAINT WHITE (8175 5225);
DISPLAY INVISIBLE (8175 5225);
FORCEPROP 1 LAST PART_NUMBER CH622KMEB02
J 0
(8175 4925);
DISPLAY 0.489362 (8175 4925);
PAINT SKYBLUE (8175 4925);
DISPLAY INVISIBLE (8175 4925);
FORCEADD Q_CAP..1
(8125 5875);
FORCEPROP 1 LAST LOCATION C2116
J 0
(8175 5975);
DISPLAY 0.489362 (8175 5975);
PAINT SKYBLUE (8175 5975);
FORCEPROP 2 LAST $SEC 1
J 0
(8175 6075);
DISPLAY 0.680851 (8175 6075);
PAINT MONO (8175 6075);
DISPLAY INVISIBLE (8175 6075);
FORCEPROP 2 LAST CDS_SEC 1
J 0
(8175 6075);
DISPLAY 1.021277 (8175 6075);
DISPLAY INVISIBLE (8175 6075);
FORCEPROP 1 LASTPIN (8125 5975) $PN 1
J 0
(8135 5955);
DISPLAY 0.489362 (8135 5955);
FORCEPROP 1 LASTPIN (8125 5775) $PN 2
J 0
(8135 5755);
DISPLAY 0.489362 (8135 5755);
FORCEPROP 1 LAST MATERIAL X6S
J 0
(8175 5775);
DISPLAY 0.489362 (8175 5775);
PAINT SKYBLUE (8175 5775);
FORCEPROP 1 LAST TOLERANCE 20%
J 0
(8175 5825);
DISPLAY 0.489362 (8175 5825);
PAINT SKYBLUE (8175 5825);
FORCEPROP 1 LAST VALUE 22UF
J 0
(8175 5925);
DISPLAY 0.489362 (8175 5925);
PAINT SKYBLUE (8175 5925);
FORCEPROP 1 LAST VOLTAGE 4V
J 0
(8175 5875);
DISPLAY 0.489362 (8175 5875);
PAINT SKYBLUE (8175 5875);
FORCEPROP 1 LAST PACK_TYPE C0402
J 0
(8175 5675);
DISPLAY 0.489362 (8175 5675);
PAINT SKYBLUE (8175 5675);
FORCEPROP 2 LAST CDS_LIB pure_quanta
J 0
(8125 5875);
PAINT MONO (8125 5875);
DISPLAY INVISIBLE (8125 5875);
FORCEPROP 1 LAST PATH I154
J 0
(8175 6025);
DISPLAY 0.978723 (8175 6025);
PAINT WHITE (8175 6025);
DISPLAY INVISIBLE (8175 6025);
FORCEPROP 1 LAST PART_NUMBER CH622KMEB02
J 0
(8175 5725);
DISPLAY 0.489362 (8175 5725);
PAINT SKYBLUE (8175 5725);
DISPLAY INVISIBLE (8175 5725);
FORCEADD Q_CAP..1
(8600 1375);
FORCEPROP 1 LAST LOCATION C3921
J 0
(8650 1475);
DISPLAY 0.489362 (8650 1475);
PAINT SKYBLUE (8650 1475);
FORCEPROP 2 LAST $SEC 1
J 0
(8650 1575);
DISPLAY 0.680851 (8650 1575);
PAINT MONO (8650 1575);
DISPLAY INVISIBLE (8650 1575);
FORCEPROP 2 LAST CDS_SEC 1
J 0
(8650 1575);
DISPLAY 1.021277 (8650 1575);
DISPLAY INVISIBLE (8650 1575);
FORCEPROP 1 LASTPIN (8600 1475) $PN 1
J 0
(8610 1455);
DISPLAY 0.489362 (8610 1455);
FORCEPROP 1 LASTPIN (8600 1275) $PN 2
J 0
(8610 1255);
DISPLAY 0.489362 (8610 1255);
FORCEPROP 1 LAST MATERIAL X6S
J 0
(8650 1275);
DISPLAY 0.489362 (8650 1275);
PAINT SKYBLUE (8650 1275);
FORCEPROP 1 LAST TOLERANCE 20%
J 0
(8650 1325);
DISPLAY 0.489362 (8650 1325);
PAINT SKYBLUE (8650 1325);
FORCEPROP 1 LAST VALUE 22UF
J 0
(8650 1425);
DISPLAY 0.489362 (8650 1425);
PAINT SKYBLUE (8650 1425);
FORCEPROP 1 LAST VOLTAGE 4V
J 0
(8650 1375);
DISPLAY 0.489362 (8650 1375);
PAINT SKYBLUE (8650 1375);
FORCEPROP 1 LAST PACK_TYPE C0402
J 0
(8650 1175);
DISPLAY 0.489362 (8650 1175);
PAINT SKYBLUE (8650 1175);
FORCEPROP 2 LAST CDS_LIB pure_quanta
J 0
(8600 1375);
PAINT MONO (8600 1375);
DISPLAY INVISIBLE (8600 1375);
FORCEPROP 1 LAST PATH I155
J 0
(8650 1525);
DISPLAY 0.978723 (8650 1525);
PAINT WHITE (8650 1525);
DISPLAY INVISIBLE (8650 1525);
FORCEPROP 1 LAST PART_NUMBER CH622KMEB02
J 0
(8650 1225);
DISPLAY 0.489362 (8650 1225);
PAINT SKYBLUE (8650 1225);
DISPLAY INVISIBLE (8650 1225);
FORCEADD UNIVERSAL_GND..1
(9000 1000);
FORCEPROP 3 LASTPIN (9000 1050) SIG_NAME GND\g
J 0
(9010 1060);
DISPLAY 0.659574 (9010 1060);
PAINT MONO (9010 1060);
DISPLAY INVISIBLE (9010 1060);
FORCEPROP 2 LAST CDS_LIB pure_quanta_power
J 0
(9000 1000);
PAINT MONO (9000 1000);
DISPLAY INVISIBLE (9000 1000);
FORCEPROP 1 LAST HDL_POWER GND
J 1
(9025 925);
DISPLAY 0.872340 (9025 925);
PAINT GREEN (9025 925);
DISPLAY INVISIBLE (9025 925);
FORCEPROP 1 LAST PATH I156
J 0
(9075 1000);
DISPLAY 0.872340 (9075 1000);
PAINT AQUA (9075 1000);
DISPLAY INVISIBLE (9075 1000);
FORCEADD Q_CAP..1
(9000 1375);
FORCEPROP 1 LAST LOCATION C3922
J 0
(9050 1475);
DISPLAY 0.489362 (9050 1475);
PAINT SKYBLUE (9050 1475);
FORCEPROP 2 LAST $SEC 1
J 0
(9050 1575);
DISPLAY 0.680851 (9050 1575);
PAINT MONO (9050 1575);
DISPLAY INVISIBLE (9050 1575);
FORCEPROP 2 LAST CDS_SEC 1
J 0
(9050 1575);
DISPLAY 1.021277 (9050 1575);
DISPLAY INVISIBLE (9050 1575);
FORCEPROP 1 LASTPIN (9000 1475) $PN 1
J 0
(9010 1455);
DISPLAY 0.489362 (9010 1455);
FORCEPROP 1 LASTPIN (9000 1275) $PN 2
J 0
(9010 1255);
DISPLAY 0.489362 (9010 1255);
FORCEPROP 1 LAST MATERIAL X6S
J 0
(9050 1275);
DISPLAY 0.489362 (9050 1275);
PAINT SKYBLUE (9050 1275);
FORCEPROP 1 LAST TOLERANCE 20%
J 0
(9050 1325);
DISPLAY 0.489362 (9050 1325);
PAINT SKYBLUE (9050 1325);
FORCEPROP 1 LAST VALUE 22UF
J 0
(9050 1425);
DISPLAY 0.489362 (9050 1425);
PAINT SKYBLUE (9050 1425);
FORCEPROP 1 LAST VOLTAGE 4V
J 0
(9050 1375);
DISPLAY 0.489362 (9050 1375);
PAINT SKYBLUE (9050 1375);
FORCEPROP 1 LAST PACK_TYPE C0402
J 0
(9050 1175);
DISPLAY 0.489362 (9050 1175);
PAINT SKYBLUE (9050 1175);
FORCEPROP 2 LAST CDS_LIB pure_quanta
J 0
(9000 1375);
PAINT MONO (9000 1375);
DISPLAY INVISIBLE (9000 1375);
FORCEPROP 1 LAST PATH I157
J 0
(9050 1525);
DISPLAY 0.978723 (9050 1525);
PAINT WHITE (9050 1525);
DISPLAY INVISIBLE (9050 1525);
FORCEPROP 1 LAST PART_NUMBER CH622KMEB02
J 0
(9050 1225);
DISPLAY 0.489362 (9050 1225);
PAINT SKYBLUE (9050 1225);
DISPLAY INVISIBLE (9050 1225);
FORCEADD UNIVERSAL_GND..1
(9000 1650);
FORCEPROP 3 LASTPIN (9000 1700) SIG_NAME GND\g
J 0
(9010 1710);
DISPLAY 0.659574 (9010 1710);
PAINT MONO (9010 1710);
DISPLAY INVISIBLE (9010 1710);
FORCEPROP 2 LAST CDS_LIB pure_quanta_power
J 0
(9000 1650);
PAINT MONO (9000 1650);
DISPLAY INVISIBLE (9000 1650);
FORCEPROP 1 LAST HDL_POWER GND
J 1
(9025 1575);
DISPLAY 0.872340 (9025 1575);
PAINT GREEN (9025 1575);
DISPLAY INVISIBLE (9025 1575);
FORCEPROP 1 LAST PATH I158
J 0
(9075 1650);
DISPLAY 0.872340 (9075 1650);
PAINT AQUA (9075 1650);
DISPLAY INVISIBLE (9075 1650);
FORCEADD Q_CAP..1
(8600 2025);
FORCEPROP 1 LAST LOCATION C2126
J 0
(8650 2125);
DISPLAY 0.489362 (8650 2125);
PAINT SKYBLUE (8650 2125);
FORCEPROP 2 LAST $SEC 1
J 0
(8650 2225);
DISPLAY 0.680851 (8650 2225);
PAINT MONO (8650 2225);
DISPLAY INVISIBLE (8650 2225);
FORCEPROP 2 LAST CDS_SEC 1
J 0
(8650 2225);
DISPLAY 1.021277 (8650 2225);
DISPLAY INVISIBLE (8650 2225);
FORCEPROP 1 LASTPIN (8600 2125) $PN 1
J 0
(8610 2105);
DISPLAY 0.489362 (8610 2105);
FORCEPROP 1 LASTPIN (8600 1925) $PN 2
J 0
(8610 1905);
DISPLAY 0.489362 (8610 1905);
FORCEPROP 1 LAST MATERIAL X6S
J 0
(8650 1925);
DISPLAY 0.489362 (8650 1925);
PAINT SKYBLUE (8650 1925);
FORCEPROP 1 LAST TOLERANCE 20%
J 0
(8650 1975);
DISPLAY 0.489362 (8650 1975);
PAINT SKYBLUE (8650 1975);
FORCEPROP 1 LAST VALUE 22UF
J 0
(8650 2075);
DISPLAY 0.489362 (8650 2075);
PAINT SKYBLUE (8650 2075);
FORCEPROP 1 LAST VOLTAGE 4V
J 0
(8650 2025);
DISPLAY 0.489362 (8650 2025);
PAINT SKYBLUE (8650 2025);
FORCEPROP 1 LAST PACK_TYPE C0402
J 0
(8650 1825);
DISPLAY 0.489362 (8650 1825);
PAINT SKYBLUE (8650 1825);
FORCEPROP 2 LAST CDS_LIB pure_quanta
J 0
(8600 2025);
PAINT MONO (8600 2025);
DISPLAY INVISIBLE (8600 2025);
FORCEPROP 1 LAST PATH I159
J 0
(8650 2175);
DISPLAY 0.978723 (8650 2175);
PAINT WHITE (8650 2175);
DISPLAY INVISIBLE (8650 2175);
FORCEPROP 1 LAST PART_NUMBER CH622KMEB02
J 0
(8650 1875);
DISPLAY 0.489362 (8650 1875);
PAINT SKYBLUE (8650 1875);
DISPLAY INVISIBLE (8650 1875);
FORCEADD Q_CAP..1
(400 3850);
FORCEPROP 1 LAST LOCATION C2410
J 0
(450 3950);
DISPLAY 0.489362 (450 3950);
PAINT SKYBLUE (450 3950);
FORCEPROP 2 LAST $SEC 1
J 0
(450 4050);
DISPLAY 0.680851 (450 4050);
PAINT MONO (450 4050);
DISPLAY INVISIBLE (450 4050);
FORCEPROP 2 LAST CDS_SEC 1
J 0
(450 4050);
DISPLAY 1.021277 (450 4050);
DISPLAY INVISIBLE (450 4050);
FORCEPROP 1 LASTPIN (400 3950) $PN 1
J 0
(410 3930);
DISPLAY 0.489362 (410 3930);
FORCEPROP 1 LASTPIN (400 3750) $PN 2
J 0
(410 3730);
DISPLAY 0.489362 (410 3730);
FORCEPROP 1 LAST MATERIAL X6S
J 0
(450 3750);
DISPLAY 0.489362 (450 3750);
PAINT SKYBLUE (450 3750);
FORCEPROP 1 LAST TOLERANCE 20%
J 0
(450 3800);
DISPLAY 0.489362 (450 3800);
PAINT SKYBLUE (450 3800);
FORCEPROP 1 LAST VALUE 22UF
J 0
(450 3900);
DISPLAY 0.489362 (450 3900);
PAINT SKYBLUE (450 3900);
FORCEPROP 1 LAST VOLTAGE 4V
J 0
(450 3850);
DISPLAY 0.489362 (450 3850);
PAINT SKYBLUE (450 3850);
FORCEPROP 1 LAST PACK_TYPE C0402
J 0
(450 3650);
DISPLAY 0.489362 (450 3650);
PAINT SKYBLUE (450 3650);
FORCEPROP 2 LAST CDS_LIB pure_quanta
J 0
(400 3850);
PAINT MONO (400 3850);
DISPLAY INVISIBLE (400 3850);
FORCEPROP 1 LAST PATH I16
J 0
(450 4000);
DISPLAY 0.978723 (450 4000);
PAINT WHITE (450 4000);
DISPLAY INVISIBLE (450 4000);
FORCEPROP 1 LAST PART_NUMBER CH622KMEB02
J 0
(450 3700);
DISPLAY 0.489362 (450 3700);
PAINT SKYBLUE (450 3700);
DISPLAY INVISIBLE (450 3700);
FORCEADD Q_CAP..1
(8600 2650);
FORCEPROP 1 LAST LOCATION C2125
J 0
(8650 2750);
DISPLAY 0.489362 (8650 2750);
PAINT SKYBLUE (8650 2750);
FORCEPROP 2 LAST $SEC 1
J 0
(8650 2850);
DISPLAY 0.680851 (8650 2850);
PAINT MONO (8650 2850);
DISPLAY INVISIBLE (8650 2850);
FORCEPROP 2 LAST CDS_SEC 1
J 0
(8650 2850);
DISPLAY 1.021277 (8650 2850);
DISPLAY INVISIBLE (8650 2850);
FORCEPROP 1 LASTPIN (8600 2750) $PN 1
J 0
(8610 2730);
DISPLAY 0.489362 (8610 2730);
FORCEPROP 1 LASTPIN (8600 2550) $PN 2
J 0
(8610 2530);
DISPLAY 0.489362 (8610 2530);
FORCEPROP 1 LAST MATERIAL X6S
J 0
(8650 2550);
DISPLAY 0.489362 (8650 2550);
PAINT SKYBLUE (8650 2550);
FORCEPROP 1 LAST TOLERANCE 20%
J 0
(8650 2600);
DISPLAY 0.489362 (8650 2600);
PAINT SKYBLUE (8650 2600);
FORCEPROP 1 LAST VALUE 22UF
J 0
(8650 2700);
DISPLAY 0.489362 (8650 2700);
PAINT SKYBLUE (8650 2700);
FORCEPROP 1 LAST VOLTAGE 4V
J 0
(8650 2650);
DISPLAY 0.489362 (8650 2650);
PAINT SKYBLUE (8650 2650);
FORCEPROP 1 LAST PACK_TYPE C0402
J 0
(8650 2450);
DISPLAY 0.489362 (8650 2450);
PAINT SKYBLUE (8650 2450);
FORCEPROP 2 LAST CDS_LIB pure_quanta
J 0
(8600 2650);
PAINT MONO (8600 2650);
DISPLAY INVISIBLE (8600 2650);
FORCEPROP 1 LAST PATH I160
J 0
(8650 2800);
DISPLAY 0.978723 (8650 2800);
PAINT WHITE (8650 2800);
DISPLAY INVISIBLE (8650 2800);
FORCEPROP 1 LAST PART_NUMBER CH622KMEB02
J 0
(8650 2500);
DISPLAY 0.489362 (8650 2500);
PAINT SKYBLUE (8650 2500);
DISPLAY INVISIBLE (8650 2500);
FORCEADD Q_CAP..1
(9000 2025);
FORCEPROP 1 LAST LOCATION C2511
J 0
(9050 2125);
DISPLAY 0.489362 (9050 2125);
PAINT SKYBLUE (9050 2125);
FORCEPROP 2 LAST $SEC 1
J 0
(9050 2225);
DISPLAY 0.680851 (9050 2225);
PAINT MONO (9050 2225);
DISPLAY INVISIBLE (9050 2225);
FORCEPROP 2 LAST CDS_SEC 1
J 0
(9050 2225);
DISPLAY 1.021277 (9050 2225);
DISPLAY INVISIBLE (9050 2225);
FORCEPROP 1 LASTPIN (9000 2125) $PN 1
J 0
(9010 2105);
DISPLAY 0.489362 (9010 2105);
FORCEPROP 1 LASTPIN (9000 1925) $PN 2
J 0
(9010 1905);
DISPLAY 0.489362 (9010 1905);
FORCEPROP 1 LAST MATERIAL X6S
J 0
(9050 1925);
DISPLAY 0.489362 (9050 1925);
PAINT SKYBLUE (9050 1925);
FORCEPROP 1 LAST TOLERANCE 20%
J 0
(9050 1975);
DISPLAY 0.489362 (9050 1975);
PAINT SKYBLUE (9050 1975);
FORCEPROP 1 LAST VALUE 22UF
J 0
(9050 2075);
DISPLAY 0.489362 (9050 2075);
PAINT SKYBLUE (9050 2075);
FORCEPROP 1 LAST VOLTAGE 4V
J 0
(9050 2025);
DISPLAY 0.489362 (9050 2025);
PAINT SKYBLUE (9050 2025);
FORCEPROP 1 LAST PACK_TYPE C0402
J 0
(9050 1825);
DISPLAY 0.489362 (9050 1825);
PAINT SKYBLUE (9050 1825);
FORCEPROP 2 LAST CDS_LIB pure_quanta
J 0
(9000 2025);
PAINT MONO (9000 2025);
DISPLAY INVISIBLE (9000 2025);
FORCEPROP 1 LAST PATH I161
J 0
(9050 2175);
DISPLAY 0.978723 (9050 2175);
PAINT WHITE (9050 2175);
DISPLAY INVISIBLE (9050 2175);
FORCEPROP 1 LAST PART_NUMBER CH622KMEB02
J 0
(9050 1875);
DISPLAY 0.489362 (9050 1875);
PAINT SKYBLUE (9050 1875);
DISPLAY INVISIBLE (9050 1875);
FORCEADD UNIVERSAL_GND..1
(9000 2300);
FORCEPROP 3 LASTPIN (9000 2350) SIG_NAME GND\g
J 0
(9010 2360);
DISPLAY 0.659574 (9010 2360);
PAINT MONO (9010 2360);
DISPLAY INVISIBLE (9010 2360);
FORCEPROP 2 LAST CDS_LIB pure_quanta_power
J 0
(9000 2300);
PAINT MONO (9000 2300);
DISPLAY INVISIBLE (9000 2300);
FORCEPROP 1 LAST HDL_POWER GND
J 1
(9025 2225);
DISPLAY 0.872340 (9025 2225);
PAINT GREEN (9025 2225);
DISPLAY INVISIBLE (9025 2225);
FORCEPROP 1 LAST PATH I162
J 0
(9075 2300);
DISPLAY 0.872340 (9075 2300);
PAINT AQUA (9075 2300);
DISPLAY INVISIBLE (9075 2300);
FORCEADD Q_CAP..1
(9000 2650);
FORCEPROP 1 LAST LOCATION C2510
J 0
(9050 2750);
DISPLAY 0.489362 (9050 2750);
PAINT SKYBLUE (9050 2750);
FORCEPROP 2 LAST $SEC 1
J 0
(9050 2850);
DISPLAY 0.680851 (9050 2850);
PAINT MONO (9050 2850);
DISPLAY INVISIBLE (9050 2850);
FORCEPROP 2 LAST CDS_SEC 1
J 0
(9050 2850);
DISPLAY 1.021277 (9050 2850);
DISPLAY INVISIBLE (9050 2850);
FORCEPROP 1 LASTPIN (9000 2750) $PN 1
J 0
(9010 2730);
DISPLAY 0.489362 (9010 2730);
FORCEPROP 1 LASTPIN (9000 2550) $PN 2
J 0
(9010 2530);
DISPLAY 0.489362 (9010 2530);
FORCEPROP 1 LAST MATERIAL X6S
J 0
(9050 2550);
DISPLAY 0.489362 (9050 2550);
PAINT SKYBLUE (9050 2550);
FORCEPROP 1 LAST TOLERANCE 20%
J 0
(9050 2600);
DISPLAY 0.489362 (9050 2600);
PAINT SKYBLUE (9050 2600);
FORCEPROP 1 LAST VALUE 22UF
J 0
(9050 2700);
DISPLAY 0.489362 (9050 2700);
PAINT SKYBLUE (9050 2700);
FORCEPROP 1 LAST VOLTAGE 4V
J 0
(9050 2650);
DISPLAY 0.489362 (9050 2650);
PAINT SKYBLUE (9050 2650);
FORCEPROP 1 LAST PACK_TYPE C0402
J 0
(9050 2450);
DISPLAY 0.489362 (9050 2450);
PAINT SKYBLUE (9050 2450);
FORCEPROP 2 LAST CDS_LIB pure_quanta
J 0
(9000 2650);
PAINT MONO (9000 2650);
DISPLAY INVISIBLE (9000 2650);
FORCEPROP 1 LAST PATH I163
J 0
(9050 2800);
DISPLAY 0.978723 (9050 2800);
PAINT WHITE (9050 2800);
DISPLAY INVISIBLE (9050 2800);
FORCEPROP 1 LAST PART_NUMBER CH622KMEB02
J 0
(9050 2500);
DISPLAY 0.489362 (9050 2500);
PAINT SKYBLUE (9050 2500);
DISPLAY INVISIBLE (9050 2500);
FORCEADD Q_CAP..1
(8600 3325);
FORCEPROP 1 LAST LOCATION C2124
J 0
(8650 3425);
DISPLAY 0.489362 (8650 3425);
PAINT SKYBLUE (8650 3425);
FORCEPROP 2 LAST $SEC 1
J 0
(8650 3525);
DISPLAY 0.680851 (8650 3525);
PAINT MONO (8650 3525);
DISPLAY INVISIBLE (8650 3525);
FORCEPROP 2 LAST CDS_SEC 1
J 0
(8650 3525);
DISPLAY 1.021277 (8650 3525);
DISPLAY INVISIBLE (8650 3525);
FORCEPROP 1 LASTPIN (8600 3425) $PN 1
J 0
(8610 3405);
DISPLAY 0.489362 (8610 3405);
FORCEPROP 1 LASTPIN (8600 3225) $PN 2
J 0
(8610 3205);
DISPLAY 0.489362 (8610 3205);
FORCEPROP 1 LAST MATERIAL X6S
J 0
(8650 3225);
DISPLAY 0.489362 (8650 3225);
PAINT SKYBLUE (8650 3225);
FORCEPROP 1 LAST TOLERANCE 20%
J 0
(8650 3275);
DISPLAY 0.489362 (8650 3275);
PAINT SKYBLUE (8650 3275);
FORCEPROP 1 LAST VALUE 22UF
J 0
(8650 3375);
DISPLAY 0.489362 (8650 3375);
PAINT SKYBLUE (8650 3375);
FORCEPROP 1 LAST VOLTAGE 4V
J 0
(8650 3325);
DISPLAY 0.489362 (8650 3325);
PAINT SKYBLUE (8650 3325);
FORCEPROP 1 LAST PACK_TYPE C0402
J 0
(8650 3125);
DISPLAY 0.489362 (8650 3125);
PAINT SKYBLUE (8650 3125);
FORCEPROP 2 LAST CDS_LIB pure_quanta
J 0
(8600 3325);
PAINT MONO (8600 3325);
DISPLAY INVISIBLE (8600 3325);
FORCEPROP 1 LAST PATH I164
J 0
(8650 3475);
DISPLAY 0.978723 (8650 3475);
PAINT WHITE (8650 3475);
DISPLAY INVISIBLE (8650 3475);
FORCEPROP 1 LAST PART_NUMBER CH622KMEB02
J 0
(8650 3175);
DISPLAY 0.489362 (8650 3175);
PAINT SKYBLUE (8650 3175);
DISPLAY INVISIBLE (8650 3175);
FORCEADD UNIVERSAL_GND..1
(9000 2950);
FORCEPROP 3 LASTPIN (9000 3000) SIG_NAME GND\g
J 0
(9010 3010);
DISPLAY 0.659574 (9010 3010);
PAINT MONO (9010 3010);
DISPLAY INVISIBLE (9010 3010);
FORCEPROP 2 LAST CDS_LIB pure_quanta_power
J 0
(9000 2950);
PAINT MONO (9000 2950);
DISPLAY INVISIBLE (9000 2950);
FORCEPROP 1 LAST HDL_POWER GND
J 1
(9025 2875);
DISPLAY 0.872340 (9025 2875);
PAINT GREEN (9025 2875);
DISPLAY INVISIBLE (9025 2875);
FORCEPROP 1 LAST PATH I165
J 0
(9075 2950);
DISPLAY 0.872340 (9075 2950);
PAINT AQUA (9075 2950);
DISPLAY INVISIBLE (9075 2950);
FORCEADD Q_CAP..1
(9000 3325);
FORCEPROP 1 LAST LOCATION C2128
J 0
(9050 3425);
DISPLAY 0.489362 (9050 3425);
PAINT SKYBLUE (9050 3425);
FORCEPROP 2 LAST $SEC 1
J 0
(9050 3525);
DISPLAY 0.680851 (9050 3525);
PAINT MONO (9050 3525);
DISPLAY INVISIBLE (9050 3525);
FORCEPROP 2 LAST CDS_SEC 1
J 0
(9050 3525);
DISPLAY 1.021277 (9050 3525);
DISPLAY INVISIBLE (9050 3525);
FORCEPROP 1 LASTPIN (9000 3425) $PN 1
J 0
(9010 3405);
DISPLAY 0.489362 (9010 3405);
FORCEPROP 1 LASTPIN (9000 3225) $PN 2
J 0
(9010 3205);
DISPLAY 0.489362 (9010 3205);
FORCEPROP 1 LAST MATERIAL X6S
J 0
(9050 3225);
DISPLAY 0.489362 (9050 3225);
PAINT SKYBLUE (9050 3225);
FORCEPROP 1 LAST TOLERANCE 20%
J 0
(9050 3275);
DISPLAY 0.489362 (9050 3275);
PAINT SKYBLUE (9050 3275);
FORCEPROP 1 LAST VALUE 22UF
J 0
(9050 3375);
DISPLAY 0.489362 (9050 3375);
PAINT SKYBLUE (9050 3375);
FORCEPROP 1 LAST VOLTAGE 4V
J 0
(9050 3325);
DISPLAY 0.489362 (9050 3325);
PAINT SKYBLUE (9050 3325);
FORCEPROP 1 LAST PACK_TYPE C0402
J 0
(9050 3125);
DISPLAY 0.489362 (9050 3125);
PAINT SKYBLUE (9050 3125);
FORCEPROP 2 LAST CDS_LIB pure_quanta
J 0
(9000 3325);
PAINT MONO (9000 3325);
DISPLAY INVISIBLE (9000 3325);
FORCEPROP 1 LAST PATH I166
J 0
(9050 3475);
DISPLAY 0.978723 (9050 3475);
PAINT WHITE (9050 3475);
DISPLAY INVISIBLE (9050 3475);
FORCEPROP 1 LAST PART_NUMBER CH622KMEB02
J 0
(9050 3175);
DISPLAY 0.489362 (9050 3175);
PAINT SKYBLUE (9050 3175);
DISPLAY INVISIBLE (9050 3175);
FORCEADD UNIVERSAL_GND..1
(8975 4700);
FORCEPROP 3 LASTPIN (8975 4750) SIG_NAME GND\g
J 0
(8985 4760);
DISPLAY 0.659574 (8985 4760);
PAINT MONO (8985 4760);
DISPLAY INVISIBLE (8985 4760);
FORCEPROP 2 LAST CDS_LIB pure_quanta_power
J 0
(8975 4700);
PAINT MONO (8975 4700);
DISPLAY INVISIBLE (8975 4700);
FORCEPROP 1 LAST HDL_POWER GND
J 1
(9000 4625);
DISPLAY 0.872340 (9000 4625);
PAINT GREEN (9000 4625);
DISPLAY INVISIBLE (9000 4625);
FORCEPROP 1 LAST PATH I167
J 0
(9050 4700);
DISPLAY 0.872340 (9050 4700);
PAINT AQUA (9050 4700);
DISPLAY INVISIBLE (9050 4700);
FORCEADD Q_CAP..1
(8575 5075);
FORCEPROP 1 LAST LOCATION C2123
J 0
(8625 5175);
DISPLAY 0.489362 (8625 5175);
PAINT SKYBLUE (8625 5175);
FORCEPROP 2 LAST $SEC 1
J 0
(8625 5275);
DISPLAY 0.680851 (8625 5275);
PAINT MONO (8625 5275);
DISPLAY INVISIBLE (8625 5275);
FORCEPROP 2 LAST CDS_SEC 1
J 0
(8625 5275);
DISPLAY 1.021277 (8625 5275);
DISPLAY INVISIBLE (8625 5275);
FORCEPROP 1 LASTPIN (8575 5175) $PN 1
J 0
(8585 5155);
DISPLAY 0.489362 (8585 5155);
FORCEPROP 1 LASTPIN (8575 4975) $PN 2
J 0
(8585 4955);
DISPLAY 0.489362 (8585 4955);
FORCEPROP 1 LAST MATERIAL X6S
J 0
(8625 4975);
DISPLAY 0.489362 (8625 4975);
PAINT SKYBLUE (8625 4975);
FORCEPROP 1 LAST TOLERANCE 20%
J 0
(8625 5025);
DISPLAY 0.489362 (8625 5025);
PAINT SKYBLUE (8625 5025);
FORCEPROP 1 LAST VALUE 22UF
J 0
(8625 5125);
DISPLAY 0.489362 (8625 5125);
PAINT SKYBLUE (8625 5125);
FORCEPROP 1 LAST VOLTAGE 4V
J 0
(8625 5075);
DISPLAY 0.489362 (8625 5075);
PAINT SKYBLUE (8625 5075);
FORCEPROP 1 LAST PACK_TYPE C0402
J 0
(8625 4875);
DISPLAY 0.489362 (8625 4875);
PAINT SKYBLUE (8625 4875);
FORCEPROP 2 LAST CDS_LIB pure_quanta
J 0
(8575 5075);
PAINT MONO (8575 5075);
DISPLAY INVISIBLE (8575 5075);
FORCEPROP 1 LAST PATH I168
J 0
(8625 5225);
DISPLAY 0.978723 (8625 5225);
PAINT WHITE (8625 5225);
DISPLAY INVISIBLE (8625 5225);
FORCEPROP 1 LAST PART_NUMBER CH622KMEB02
J 0
(8625 4925);
DISPLAY 0.489362 (8625 4925);
PAINT SKYBLUE (8625 4925);
DISPLAY INVISIBLE (8625 4925);
FORCEADD Q_CAP..1
(8575 5875);
FORCEPROP 1 LAST LOCATION C2122
J 0
(8625 5975);
DISPLAY 0.489362 (8625 5975);
PAINT SKYBLUE (8625 5975);
FORCEPROP 2 LAST $SEC 1
J 0
(8625 6075);
DISPLAY 0.680851 (8625 6075);
PAINT MONO (8625 6075);
DISPLAY INVISIBLE (8625 6075);
FORCEPROP 2 LAST CDS_SEC 1
J 0
(8625 6075);
DISPLAY 1.021277 (8625 6075);
DISPLAY INVISIBLE (8625 6075);
FORCEPROP 1 LASTPIN (8575 5975) $PN 1
J 0
(8585 5955);
DISPLAY 0.489362 (8585 5955);
FORCEPROP 1 LASTPIN (8575 5775) $PN 2
J 0
(8585 5755);
DISPLAY 0.489362 (8585 5755);
FORCEPROP 1 LAST MATERIAL X6S
J 0
(8625 5775);
DISPLAY 0.489362 (8625 5775);
PAINT SKYBLUE (8625 5775);
FORCEPROP 1 LAST TOLERANCE 20%
J 0
(8625 5825);
DISPLAY 0.489362 (8625 5825);
PAINT SKYBLUE (8625 5825);
FORCEPROP 1 LAST VALUE 22UF
J 0
(8625 5925);
DISPLAY 0.489362 (8625 5925);
PAINT SKYBLUE (8625 5925);
FORCEPROP 1 LAST VOLTAGE 4V
J 0
(8625 5875);
DISPLAY 0.489362 (8625 5875);
PAINT SKYBLUE (8625 5875);
FORCEPROP 1 LAST PACK_TYPE C0402
J 0
(8625 5675);
DISPLAY 0.489362 (8625 5675);
PAINT SKYBLUE (8625 5675);
FORCEPROP 2 LAST CDS_LIB pure_quanta
J 0
(8575 5875);
PAINT MONO (8575 5875);
DISPLAY INVISIBLE (8575 5875);
FORCEPROP 1 LAST PATH I169
J 0
(8625 6025);
DISPLAY 0.978723 (8625 6025);
PAINT WHITE (8625 6025);
DISPLAY INVISIBLE (8625 6025);
FORCEPROP 1 LAST PART_NUMBER CH622KMEB02
J 0
(8625 5725);
DISPLAY 0.489362 (8625 5725);
PAINT SKYBLUE (8625 5725);
DISPLAY INVISIBLE (8625 5725);
FORCEADD Q_CAP..1
(850 3150);
FORCEPROP 1 LAST LOCATION C2418
J 0
(900 3250);
DISPLAY 0.489362 (900 3250);
PAINT SKYBLUE (900 3250);
FORCEPROP 2 LAST $SEC 1
J 0
(900 3350);
DISPLAY 0.680851 (900 3350);
PAINT MONO (900 3350);
DISPLAY INVISIBLE (900 3350);
FORCEPROP 2 LAST CDS_SEC 1
J 0
(900 3350);
DISPLAY 1.021277 (900 3350);
DISPLAY INVISIBLE (900 3350);
FORCEPROP 1 LASTPIN (850 3250) $PN 1
J 0
(860 3230);
DISPLAY 0.489362 (860 3230);
FORCEPROP 1 LASTPIN (850 3050) $PN 2
J 0
(860 3030);
DISPLAY 0.489362 (860 3030);
FORCEPROP 1 LAST MATERIAL X6S
J 0
(900 3050);
DISPLAY 0.489362 (900 3050);
PAINT SKYBLUE (900 3050);
FORCEPROP 1 LAST TOLERANCE 20%
J 0
(900 3100);
DISPLAY 0.489362 (900 3100);
PAINT SKYBLUE (900 3100);
FORCEPROP 1 LAST VALUE 22UF
J 0
(900 3200);
DISPLAY 0.489362 (900 3200);
PAINT SKYBLUE (900 3200);
FORCEPROP 1 LAST VOLTAGE 4V
J 0
(900 3150);
DISPLAY 0.489362 (900 3150);
PAINT SKYBLUE (900 3150);
FORCEPROP 1 LAST PACK_TYPE C0402
J 0
(900 2950);
DISPLAY 0.489362 (900 2950);
PAINT SKYBLUE (900 2950);
FORCEPROP 2 LAST CDS_LIB pure_quanta
J 0
(850 3150);
PAINT MONO (850 3150);
DISPLAY INVISIBLE (850 3150);
FORCEPROP 1 LAST PATH I17
J 0
(900 3300);
DISPLAY 0.978723 (900 3300);
PAINT WHITE (900 3300);
DISPLAY INVISIBLE (900 3300);
FORCEPROP 1 LAST PART_NUMBER CH622KMEB02
J 0
(900 3000);
DISPLAY 0.489362 (900 3000);
PAINT SKYBLUE (900 3000);
DISPLAY INVISIBLE (900 3000);
FORCEADD Q_CAP..1
(8975 5075);
FORCEPROP 1 LAST LOCATION C2509
J 0
(9025 5175);
DISPLAY 0.489362 (9025 5175);
PAINT SKYBLUE (9025 5175);
FORCEPROP 2 LAST $SEC 1
J 0
(9025 5275);
DISPLAY 0.680851 (9025 5275);
PAINT MONO (9025 5275);
DISPLAY INVISIBLE (9025 5275);
FORCEPROP 2 LAST CDS_SEC 1
J 0
(9025 5275);
DISPLAY 1.021277 (9025 5275);
DISPLAY INVISIBLE (9025 5275);
FORCEPROP 1 LASTPIN (8975 5175) $PN 1
J 0
(8985 5155);
DISPLAY 0.489362 (8985 5155);
FORCEPROP 1 LASTPIN (8975 4975) $PN 2
J 0
(8985 4955);
DISPLAY 0.489362 (8985 4955);
FORCEPROP 1 LAST MATERIAL X6S
J 0
(9025 4975);
DISPLAY 0.489362 (9025 4975);
PAINT SKYBLUE (9025 4975);
FORCEPROP 1 LAST TOLERANCE 20%
J 0
(9025 5025);
DISPLAY 0.489362 (9025 5025);
PAINT SKYBLUE (9025 5025);
FORCEPROP 1 LAST VALUE 22UF
J 0
(9025 5125);
DISPLAY 0.489362 (9025 5125);
PAINT SKYBLUE (9025 5125);
FORCEPROP 1 LAST VOLTAGE 4V
J 0
(9025 5075);
DISPLAY 0.489362 (9025 5075);
PAINT SKYBLUE (9025 5075);
FORCEPROP 1 LAST PACK_TYPE C0402
J 0
(9025 4875);
DISPLAY 0.489362 (9025 4875);
PAINT SKYBLUE (9025 4875);
FORCEPROP 2 LAST CDS_LIB pure_quanta
J 0
(8975 5075);
PAINT MONO (8975 5075);
DISPLAY INVISIBLE (8975 5075);
FORCEPROP 1 LAST PATH I170
J 0
(9025 5225);
DISPLAY 0.978723 (9025 5225);
PAINT WHITE (9025 5225);
DISPLAY INVISIBLE (9025 5225);
FORCEPROP 1 LAST PART_NUMBER CH622KMEB02
J 0
(9025 4925);
DISPLAY 0.489362 (9025 4925);
PAINT SKYBLUE (9025 4925);
DISPLAY INVISIBLE (9025 4925);
FORCEADD UNIVERSAL_GND..1
(8975 5500);
FORCEPROP 3 LASTPIN (8975 5550) SIG_NAME GND\g
J 0
(8985 5560);
DISPLAY 0.659574 (8985 5560);
PAINT MONO (8985 5560);
DISPLAY INVISIBLE (8985 5560);
FORCEPROP 2 LAST CDS_LIB pure_quanta_power
J 0
(8975 5500);
PAINT MONO (8975 5500);
DISPLAY INVISIBLE (8975 5500);
FORCEPROP 1 LAST HDL_POWER GND
J 1
(9000 5425);
DISPLAY 0.872340 (9000 5425);
PAINT GREEN (9000 5425);
DISPLAY INVISIBLE (9000 5425);
FORCEPROP 1 LAST PATH I171
J 0
(9050 5500);
DISPLAY 0.872340 (9050 5500);
PAINT AQUA (9050 5500);
DISPLAY INVISIBLE (9050 5500);
FORCEADD Q_CAP..1
(8975 5875);
FORCEPROP 1 LAST LOCATION C2127
J 0
(9025 5975);
DISPLAY 0.489362 (9025 5975);
PAINT SKYBLUE (9025 5975);
FORCEPROP 2 LAST $SEC 1
J 0
(9025 6075);
DISPLAY 0.680851 (9025 6075);
PAINT MONO (9025 6075);
DISPLAY INVISIBLE (9025 6075);
FORCEPROP 2 LAST CDS_SEC 1
J 0
(9025 6075);
DISPLAY 1.021277 (9025 6075);
DISPLAY INVISIBLE (9025 6075);
FORCEPROP 1 LASTPIN (8975 5975) $PN 1
J 0
(8985 5955);
DISPLAY 0.489362 (8985 5955);
FORCEPROP 1 LASTPIN (8975 5775) $PN 2
J 0
(8985 5755);
DISPLAY 0.489362 (8985 5755);
FORCEPROP 1 LAST MATERIAL X6S
J 0
(9025 5775);
DISPLAY 0.489362 (9025 5775);
PAINT SKYBLUE (9025 5775);
FORCEPROP 1 LAST TOLERANCE 20%
J 0
(9025 5825);
DISPLAY 0.489362 (9025 5825);
PAINT SKYBLUE (9025 5825);
FORCEPROP 1 LAST VALUE 22UF
J 0
(9025 5925);
DISPLAY 0.489362 (9025 5925);
PAINT SKYBLUE (9025 5925);
FORCEPROP 1 LAST VOLTAGE 4V
J 0
(9025 5875);
DISPLAY 0.489362 (9025 5875);
PAINT SKYBLUE (9025 5875);
FORCEPROP 1 LAST PACK_TYPE C0402
J 0
(9025 5675);
DISPLAY 0.489362 (9025 5675);
PAINT SKYBLUE (9025 5675);
FORCEPROP 2 LAST CDS_LIB pure_quanta
J 0
(8975 5875);
PAINT MONO (8975 5875);
DISPLAY INVISIBLE (8975 5875);
FORCEPROP 1 LAST PATH I172
J 0
(9025 6025);
DISPLAY 0.978723 (9025 6025);
PAINT WHITE (9025 6025);
DISPLAY INVISIBLE (9025 6025);
FORCEPROP 1 LAST PART_NUMBER CH622KMEB02
J 0
(9025 5725);
DISPLAY 0.489362 (9025 5725);
PAINT SKYBLUE (9025 5725);
DISPLAY INVISIBLE (9025 5725);
FORCEADD Q_CAP..1
(2650 5875);
FORCEPROP 1 LAST LOCATION C2442
J 0
(2700 5975);
DISPLAY 0.489362 (2700 5975);
PAINT SKYBLUE (2700 5975);
FORCEPROP 2 LAST $SEC 1
J 0
(2700 6075);
DISPLAY 0.680851 (2700 6075);
PAINT MONO (2700 6075);
DISPLAY INVISIBLE (2700 6075);
FORCEPROP 2 LAST CDS_SEC 1
J 0
(2700 6075);
DISPLAY 1.021277 (2700 6075);
DISPLAY INVISIBLE (2700 6075);
FORCEPROP 1 LASTPIN (2650 5975) $PN 1
J 0
(2660 5955);
DISPLAY 0.489362 (2660 5955);
FORCEPROP 1 LASTPIN (2650 5775) $PN 2
J 0
(2660 5755);
DISPLAY 0.489362 (2660 5755);
FORCEPROP 1 LAST MATERIAL X6S
J 0
(2700 5775);
DISPLAY 0.489362 (2700 5775);
PAINT SKYBLUE (2700 5775);
FORCEPROP 1 LAST TOLERANCE 20%
J 0
(2700 5825);
DISPLAY 0.489362 (2700 5825);
PAINT SKYBLUE (2700 5825);
FORCEPROP 1 LAST VALUE 22UF
J 0
(2700 5925);
DISPLAY 0.489362 (2700 5925);
PAINT SKYBLUE (2700 5925);
FORCEPROP 1 LAST VOLTAGE 4V
J 0
(2700 5875);
DISPLAY 0.489362 (2700 5875);
PAINT SKYBLUE (2700 5875);
FORCEPROP 1 LAST PACK_TYPE C0402
J 0
(2700 5675);
DISPLAY 0.489362 (2700 5675);
PAINT SKYBLUE (2700 5675);
FORCEPROP 2 LAST CDS_LIB pure_quanta
J 0
(2650 5875);
PAINT MONO (2650 5875);
DISPLAY INVISIBLE (2650 5875);
FORCEPROP 1 LAST PATH I173
J 0
(2700 6025);
DISPLAY 0.978723 (2700 6025);
PAINT WHITE (2700 6025);
DISPLAY INVISIBLE (2700 6025);
FORCEPROP 1 LAST PART_NUMBER CH622KMEB02
J 0
(2700 5725);
DISPLAY 0.489362 (2700 5725);
PAINT SKYBLUE (2700 5725);
DISPLAY INVISIBLE (2700 5725);
FORCEADD Q_CAP..1
(2200 5875);
FORCEPROP 1 LAST LOCATION C2435
J 0
(2250 5975);
DISPLAY 0.489362 (2250 5975);
PAINT SKYBLUE (2250 5975);
FORCEPROP 2 LAST $SEC 1
J 0
(2250 6075);
DISPLAY 0.680851 (2250 6075);
PAINT MONO (2250 6075);
DISPLAY INVISIBLE (2250 6075);
FORCEPROP 2 LAST CDS_SEC 1
J 0
(2250 6075);
DISPLAY 1.021277 (2250 6075);
DISPLAY INVISIBLE (2250 6075);
FORCEPROP 1 LASTPIN (2200 5975) $PN 1
J 0
(2210 5955);
DISPLAY 0.489362 (2210 5955);
FORCEPROP 1 LASTPIN (2200 5775) $PN 2
J 0
(2210 5755);
DISPLAY 0.489362 (2210 5755);
FORCEPROP 1 LAST MATERIAL X6S
J 0
(2250 5775);
DISPLAY 0.489362 (2250 5775);
PAINT SKYBLUE (2250 5775);
FORCEPROP 1 LAST TOLERANCE 20%
J 0
(2250 5825);
DISPLAY 0.489362 (2250 5825);
PAINT SKYBLUE (2250 5825);
FORCEPROP 1 LAST VALUE 22UF
J 0
(2250 5925);
DISPLAY 0.489362 (2250 5925);
PAINT SKYBLUE (2250 5925);
FORCEPROP 1 LAST VOLTAGE 4V
J 0
(2250 5875);
DISPLAY 0.489362 (2250 5875);
PAINT SKYBLUE (2250 5875);
FORCEPROP 1 LAST PACK_TYPE C0402
J 0
(2250 5675);
DISPLAY 0.489362 (2250 5675);
PAINT SKYBLUE (2250 5675);
FORCEPROP 2 LAST CDS_LIB pure_quanta
J 0
(2200 5875);
PAINT MONO (2200 5875);
DISPLAY INVISIBLE (2200 5875);
FORCEPROP 1 LAST PATH I174
J 0
(2250 6025);
DISPLAY 0.978723 (2250 6025);
PAINT WHITE (2250 6025);
DISPLAY INVISIBLE (2250 6025);
FORCEPROP 1 LAST PART_NUMBER CH622KMEB02
J 0
(2250 5725);
DISPLAY 0.489362 (2250 5725);
PAINT SKYBLUE (2250 5725);
DISPLAY INVISIBLE (2250 5725);
FORCEADD Q_CAP..1
(1750 5875);
FORCEPROP 1 LAST LOCATION C2428
J 0
(1800 5975);
DISPLAY 0.489362 (1800 5975);
PAINT SKYBLUE (1800 5975);
FORCEPROP 2 LAST $SEC 1
J 0
(1800 6075);
DISPLAY 0.680851 (1800 6075);
PAINT MONO (1800 6075);
DISPLAY INVISIBLE (1800 6075);
FORCEPROP 2 LAST CDS_SEC 1
J 0
(1800 6075);
DISPLAY 1.021277 (1800 6075);
DISPLAY INVISIBLE (1800 6075);
FORCEPROP 1 LASTPIN (1750 5975) $PN 1
J 0
(1760 5955);
DISPLAY 0.489362 (1760 5955);
FORCEPROP 1 LASTPIN (1750 5775) $PN 2
J 0
(1760 5755);
DISPLAY 0.489362 (1760 5755);
FORCEPROP 1 LAST MATERIAL X6S
J 0
(1800 5775);
DISPLAY 0.489362 (1800 5775);
PAINT SKYBLUE (1800 5775);
FORCEPROP 1 LAST TOLERANCE 20%
J 0
(1800 5825);
DISPLAY 0.489362 (1800 5825);
PAINT SKYBLUE (1800 5825);
FORCEPROP 1 LAST VALUE 22UF
J 0
(1800 5925);
DISPLAY 0.489362 (1800 5925);
PAINT SKYBLUE (1800 5925);
FORCEPROP 1 LAST VOLTAGE 4V
J 0
(1800 5875);
DISPLAY 0.489362 (1800 5875);
PAINT SKYBLUE (1800 5875);
FORCEPROP 1 LAST PACK_TYPE C0402
J 0
(1800 5675);
DISPLAY 0.489362 (1800 5675);
PAINT SKYBLUE (1800 5675);
FORCEPROP 2 LAST CDS_LIB pure_quanta
J 0
(1750 5875);
PAINT MONO (1750 5875);
DISPLAY INVISIBLE (1750 5875);
FORCEPROP 1 LAST PATH I175
J 0
(1800 6025);
DISPLAY 0.978723 (1800 6025);
PAINT WHITE (1800 6025);
DISPLAY INVISIBLE (1800 6025);
FORCEPROP 1 LAST PART_NUMBER CH622KMEB02
J 0
(1800 5725);
DISPLAY 0.489362 (1800 5725);
PAINT SKYBLUE (1800 5725);
DISPLAY INVISIBLE (1800 5725);
FORCEADD Q_CAP..1
(850 3850);
FORCEPROP 1 LAST LOCATION C2417
J 0
(900 3950);
DISPLAY 0.489362 (900 3950);
PAINT SKYBLUE (900 3950);
FORCEPROP 2 LAST $SEC 1
J 0
(900 4050);
DISPLAY 0.680851 (900 4050);
PAINT MONO (900 4050);
DISPLAY INVISIBLE (900 4050);
FORCEPROP 2 LAST CDS_SEC 1
J 0
(900 4050);
DISPLAY 1.021277 (900 4050);
DISPLAY INVISIBLE (900 4050);
FORCEPROP 1 LASTPIN (850 3950) $PN 1
J 0
(860 3930);
DISPLAY 0.489362 (860 3930);
FORCEPROP 1 LASTPIN (850 3750) $PN 2
J 0
(860 3730);
DISPLAY 0.489362 (860 3730);
FORCEPROP 1 LAST MATERIAL X6S
J 0
(900 3750);
DISPLAY 0.489362 (900 3750);
PAINT SKYBLUE (900 3750);
FORCEPROP 1 LAST TOLERANCE 20%
J 0
(900 3800);
DISPLAY 0.489362 (900 3800);
PAINT SKYBLUE (900 3800);
FORCEPROP 1 LAST VALUE 22UF
J 0
(900 3900);
DISPLAY 0.489362 (900 3900);
PAINT SKYBLUE (900 3900);
FORCEPROP 1 LAST VOLTAGE 4V
J 0
(900 3850);
DISPLAY 0.489362 (900 3850);
PAINT SKYBLUE (900 3850);
FORCEPROP 1 LAST PACK_TYPE C0402
J 0
(900 3650);
DISPLAY 0.489362 (900 3650);
PAINT SKYBLUE (900 3650);
FORCEPROP 2 LAST CDS_LIB pure_quanta
J 0
(850 3850);
PAINT MONO (850 3850);
DISPLAY INVISIBLE (850 3850);
FORCEPROP 1 LAST PATH I18
J 0
(900 4000);
DISPLAY 0.978723 (900 4000);
PAINT WHITE (900 4000);
DISPLAY INVISIBLE (900 4000);
FORCEPROP 1 LAST PART_NUMBER CH622KMEB02
J 0
(900 3700);
DISPLAY 0.489362 (900 3700);
PAINT SKYBLUE (900 3700);
DISPLAY INVISIBLE (900 3700);
FORCEADD Q_CAP..1
(1300 2475);
FORCEPROP 1 LAST LOCATION C2426
J 0
(1350 2575);
DISPLAY 0.489362 (1350 2575);
PAINT SKYBLUE (1350 2575);
FORCEPROP 2 LAST $SEC 1
J 0
(1350 2675);
DISPLAY 0.680851 (1350 2675);
PAINT MONO (1350 2675);
DISPLAY INVISIBLE (1350 2675);
FORCEPROP 2 LAST CDS_SEC 1
J 0
(1350 2675);
DISPLAY 1.021277 (1350 2675);
DISPLAY INVISIBLE (1350 2675);
FORCEPROP 1 LASTPIN (1300 2575) $PN 1
J 0
(1310 2555);
DISPLAY 0.489362 (1310 2555);
FORCEPROP 1 LASTPIN (1300 2375) $PN 2
J 0
(1310 2355);
DISPLAY 0.489362 (1310 2355);
FORCEPROP 1 LAST MATERIAL X6S
J 0
(1350 2375);
DISPLAY 0.489362 (1350 2375);
PAINT SKYBLUE (1350 2375);
FORCEPROP 1 LAST TOLERANCE 20%
J 0
(1350 2425);
DISPLAY 0.489362 (1350 2425);
PAINT SKYBLUE (1350 2425);
FORCEPROP 1 LAST VALUE 22UF
J 0
(1350 2525);
DISPLAY 0.489362 (1350 2525);
PAINT SKYBLUE (1350 2525);
FORCEPROP 1 LAST VOLTAGE 4V
J 0
(1350 2475);
DISPLAY 0.489362 (1350 2475);
PAINT SKYBLUE (1350 2475);
FORCEPROP 1 LAST PACK_TYPE C0402
J 0
(1350 2275);
DISPLAY 0.489362 (1350 2275);
PAINT SKYBLUE (1350 2275);
FORCEPROP 2 LAST CDS_LIB pure_quanta
J 0
(1300 2475);
PAINT MONO (1300 2475);
DISPLAY INVISIBLE (1300 2475);
FORCEPROP 1 LAST PATH I19
J 0
(1350 2625);
DISPLAY 0.978723 (1350 2625);
PAINT WHITE (1350 2625);
DISPLAY INVISIBLE (1350 2625);
FORCEPROP 1 LAST PART_NUMBER CH622KMEB02
J 0
(1350 2325);
DISPLAY 0.489362 (1350 2325);
PAINT SKYBLUE (1350 2325);
DISPLAY INVISIBLE (1350 2325);
FORCEADD UNIVERSAL_POWER..1
(400 1350);
FORCEPROP 3 LASTPIN (400 1300) SIG_NAME PVDDCR_SOC_P1\g
J 0
(410 1310);
DISPLAY 0.659574 (410 1310);
PAINT MONO (410 1310);
DISPLAY INVISIBLE (410 1310);
FORCEPROP 1 LAST HDL_POWER PVDDCR_SOC_P1
J 1
(400 1400);
DISPLAY 0.489362 (400 1400);
PAINT GREEN (400 1400);
FORCEPROP 2 LAST CDS_LIB pure_quanta_power
J 0
(400 1350);
DISPLAY INVISIBLE (400 1350);
FORCEPROP 1 LAST PATH I2
J 0
(450 1375);
DISPLAY 0.872340 (450 1375);
PAINT AQUA (450 1375);
DISPLAY INVISIBLE (450 1375);
FORCEADD Q_CAP..1
(1750 2475);
FORCEPROP 1 LAST LOCATION C2433
J 0
(1800 2575);
DISPLAY 0.489362 (1800 2575);
PAINT SKYBLUE (1800 2575);
FORCEPROP 2 LAST $SEC 1
J 0
(1800 2675);
DISPLAY 0.680851 (1800 2675);
PAINT MONO (1800 2675);
DISPLAY INVISIBLE (1800 2675);
FORCEPROP 2 LAST CDS_SEC 1
J 0
(1800 2675);
DISPLAY 1.021277 (1800 2675);
DISPLAY INVISIBLE (1800 2675);
FORCEPROP 1 LASTPIN (1750 2575) $PN 1
J 0
(1760 2555);
DISPLAY 0.489362 (1760 2555);
FORCEPROP 1 LASTPIN (1750 2375) $PN 2
J 0
(1760 2355);
DISPLAY 0.489362 (1760 2355);
FORCEPROP 1 LAST MATERIAL X6S
J 0
(1800 2375);
DISPLAY 0.489362 (1800 2375);
PAINT SKYBLUE (1800 2375);
FORCEPROP 1 LAST TOLERANCE 20%
J 0
(1800 2425);
DISPLAY 0.489362 (1800 2425);
PAINT SKYBLUE (1800 2425);
FORCEPROP 1 LAST VALUE 22UF
J 0
(1800 2525);
DISPLAY 0.489362 (1800 2525);
PAINT SKYBLUE (1800 2525);
FORCEPROP 1 LAST VOLTAGE 4V
J 0
(1800 2475);
DISPLAY 0.489362 (1800 2475);
PAINT SKYBLUE (1800 2475);
FORCEPROP 1 LAST PACK_TYPE C0402
J 0
(1800 2275);
DISPLAY 0.489362 (1800 2275);
PAINT SKYBLUE (1800 2275);
FORCEPROP 2 LAST CDS_LIB pure_quanta
J 0
(1750 2475);
PAINT MONO (1750 2475);
DISPLAY INVISIBLE (1750 2475);
FORCEPROP 1 LAST PATH I20
J 0
(1800 2625);
DISPLAY 0.978723 (1800 2625);
PAINT WHITE (1800 2625);
DISPLAY INVISIBLE (1800 2625);
FORCEPROP 1 LAST PART_NUMBER CH622KMEB02
J 0
(1800 2325);
DISPLAY 0.489362 (1800 2325);
PAINT SKYBLUE (1800 2325);
DISPLAY INVISIBLE (1800 2325);
FORCEADD Q_CAP..1
(1300 3150);
FORCEPROP 1 LAST LOCATION C2425
J 0
(1350 3250);
DISPLAY 0.489362 (1350 3250);
PAINT SKYBLUE (1350 3250);
FORCEPROP 2 LAST $SEC 1
J 0
(1350 3350);
DISPLAY 0.680851 (1350 3350);
PAINT MONO (1350 3350);
DISPLAY INVISIBLE (1350 3350);
FORCEPROP 2 LAST CDS_SEC 1
J 0
(1350 3350);
DISPLAY 1.021277 (1350 3350);
DISPLAY INVISIBLE (1350 3350);
FORCEPROP 1 LASTPIN (1300 3250) $PN 1
J 0
(1310 3230);
DISPLAY 0.489362 (1310 3230);
FORCEPROP 1 LASTPIN (1300 3050) $PN 2
J 0
(1310 3030);
DISPLAY 0.489362 (1310 3030);
FORCEPROP 1 LAST MATERIAL X6S
J 0
(1350 3050);
DISPLAY 0.489362 (1350 3050);
PAINT SKYBLUE (1350 3050);
FORCEPROP 1 LAST TOLERANCE 20%
J 0
(1350 3100);
DISPLAY 0.489362 (1350 3100);
PAINT SKYBLUE (1350 3100);
FORCEPROP 1 LAST VALUE 22UF
J 0
(1350 3200);
DISPLAY 0.489362 (1350 3200);
PAINT SKYBLUE (1350 3200);
FORCEPROP 1 LAST VOLTAGE 4V
J 0
(1350 3150);
DISPLAY 0.489362 (1350 3150);
PAINT SKYBLUE (1350 3150);
FORCEPROP 1 LAST PACK_TYPE C0402
J 0
(1350 2950);
DISPLAY 0.489362 (1350 2950);
PAINT SKYBLUE (1350 2950);
FORCEPROP 2 LAST CDS_LIB pure_quanta
J 0
(1300 3150);
PAINT MONO (1300 3150);
DISPLAY INVISIBLE (1300 3150);
FORCEPROP 1 LAST PATH I21
J 0
(1350 3300);
DISPLAY 0.978723 (1350 3300);
PAINT WHITE (1350 3300);
DISPLAY INVISIBLE (1350 3300);
FORCEPROP 1 LAST PART_NUMBER CH622KMEB02
J 0
(1350 3000);
DISPLAY 0.489362 (1350 3000);
PAINT SKYBLUE (1350 3000);
DISPLAY INVISIBLE (1350 3000);
FORCEADD Q_CAP..1
(1300 3850);
FORCEPROP 1 LAST LOCATION C2424
J 0
(1350 3950);
DISPLAY 0.489362 (1350 3950);
PAINT SKYBLUE (1350 3950);
FORCEPROP 2 LAST $SEC 1
J 0
(1350 4050);
DISPLAY 0.680851 (1350 4050);
PAINT MONO (1350 4050);
DISPLAY INVISIBLE (1350 4050);
FORCEPROP 2 LAST CDS_SEC 1
J 0
(1350 4050);
DISPLAY 1.021277 (1350 4050);
DISPLAY INVISIBLE (1350 4050);
FORCEPROP 1 LASTPIN (1300 3950) $PN 1
J 0
(1310 3930);
DISPLAY 0.489362 (1310 3930);
FORCEPROP 1 LASTPIN (1300 3750) $PN 2
J 0
(1310 3730);
DISPLAY 0.489362 (1310 3730);
FORCEPROP 1 LAST MATERIAL X6S
J 0
(1350 3750);
DISPLAY 0.489362 (1350 3750);
PAINT SKYBLUE (1350 3750);
FORCEPROP 1 LAST TOLERANCE 20%
J 0
(1350 3800);
DISPLAY 0.489362 (1350 3800);
PAINT SKYBLUE (1350 3800);
FORCEPROP 1 LAST VALUE 22UF
J 0
(1350 3900);
DISPLAY 0.489362 (1350 3900);
PAINT SKYBLUE (1350 3900);
FORCEPROP 1 LAST VOLTAGE 4V
J 0
(1350 3850);
DISPLAY 0.489362 (1350 3850);
PAINT SKYBLUE (1350 3850);
FORCEPROP 1 LAST PACK_TYPE C0402
J 0
(1350 3650);
DISPLAY 0.489362 (1350 3650);
PAINT SKYBLUE (1350 3650);
FORCEPROP 2 LAST CDS_LIB pure_quanta
J 0
(1300 3850);
PAINT MONO (1300 3850);
DISPLAY INVISIBLE (1300 3850);
FORCEPROP 1 LAST PATH I22
J 0
(1350 4000);
DISPLAY 0.978723 (1350 4000);
PAINT WHITE (1350 4000);
DISPLAY INVISIBLE (1350 4000);
FORCEPROP 1 LAST PART_NUMBER CH622KMEB02
J 0
(1350 3700);
DISPLAY 0.489362 (1350 3700);
PAINT SKYBLUE (1350 3700);
DISPLAY INVISIBLE (1350 3700);
FORCEADD Q_CAP..1
(1750 3150);
FORCEPROP 1 LAST LOCATION C2432
J 0
(1800 3250);
DISPLAY 0.489362 (1800 3250);
PAINT SKYBLUE (1800 3250);
FORCEPROP 2 LAST $SEC 1
J 0
(1800 3350);
DISPLAY 0.680851 (1800 3350);
PAINT MONO (1800 3350);
DISPLAY INVISIBLE (1800 3350);
FORCEPROP 2 LAST CDS_SEC 1
J 0
(1800 3350);
DISPLAY 1.021277 (1800 3350);
DISPLAY INVISIBLE (1800 3350);
FORCEPROP 1 LASTPIN (1750 3250) $PN 1
J 0
(1760 3230);
DISPLAY 0.489362 (1760 3230);
FORCEPROP 1 LASTPIN (1750 3050) $PN 2
J 0
(1760 3030);
DISPLAY 0.489362 (1760 3030);
FORCEPROP 1 LAST MATERIAL X6S
J 0
(1800 3050);
DISPLAY 0.489362 (1800 3050);
PAINT SKYBLUE (1800 3050);
FORCEPROP 1 LAST TOLERANCE 20%
J 0
(1800 3100);
DISPLAY 0.489362 (1800 3100);
PAINT SKYBLUE (1800 3100);
FORCEPROP 1 LAST VALUE 22UF
J 0
(1800 3200);
DISPLAY 0.489362 (1800 3200);
PAINT SKYBLUE (1800 3200);
FORCEPROP 1 LAST VOLTAGE 4V
J 0
(1800 3150);
DISPLAY 0.489362 (1800 3150);
PAINT SKYBLUE (1800 3150);
FORCEPROP 1 LAST PACK_TYPE C0402
J 0
(1800 2950);
DISPLAY 0.489362 (1800 2950);
PAINT SKYBLUE (1800 2950);
FORCEPROP 2 LAST CDS_LIB pure_quanta
J 0
(1750 3150);
PAINT MONO (1750 3150);
DISPLAY INVISIBLE (1750 3150);
FORCEPROP 1 LAST PATH I23
J 0
(1800 3300);
DISPLAY 0.978723 (1800 3300);
PAINT WHITE (1800 3300);
DISPLAY INVISIBLE (1800 3300);
FORCEPROP 1 LAST PART_NUMBER CH622KMEB02
J 0
(1800 3000);
DISPLAY 0.489362 (1800 3000);
PAINT SKYBLUE (1800 3000);
DISPLAY INVISIBLE (1800 3000);
FORCEADD Q_CAP..1
(1750 3850);
FORCEPROP 1 LAST LOCATION C2431
J 0
(1800 3950);
DISPLAY 0.489362 (1800 3950);
PAINT SKYBLUE (1800 3950);
FORCEPROP 2 LAST $SEC 1
J 0
(1800 4050);
DISPLAY 0.680851 (1800 4050);
PAINT MONO (1800 4050);
DISPLAY INVISIBLE (1800 4050);
FORCEPROP 2 LAST CDS_SEC 1
J 0
(1800 4050);
DISPLAY 1.021277 (1800 4050);
DISPLAY INVISIBLE (1800 4050);
FORCEPROP 1 LASTPIN (1750 3950) $PN 1
J 0
(1760 3930);
DISPLAY 0.489362 (1760 3930);
FORCEPROP 1 LASTPIN (1750 3750) $PN 2
J 0
(1760 3730);
DISPLAY 0.489362 (1760 3730);
FORCEPROP 1 LAST MATERIAL X6S
J 0
(1800 3750);
DISPLAY 0.489362 (1800 3750);
PAINT SKYBLUE (1800 3750);
FORCEPROP 1 LAST TOLERANCE 20%
J 0
(1800 3800);
DISPLAY 0.489362 (1800 3800);
PAINT SKYBLUE (1800 3800);
FORCEPROP 1 LAST VALUE 22UF
J 0
(1800 3900);
DISPLAY 0.489362 (1800 3900);
PAINT SKYBLUE (1800 3900);
FORCEPROP 1 LAST VOLTAGE 4V
J 0
(1800 3850);
DISPLAY 0.489362 (1800 3850);
PAINT SKYBLUE (1800 3850);
FORCEPROP 1 LAST PACK_TYPE C0402
J 0
(1800 3650);
DISPLAY 0.489362 (1800 3650);
PAINT SKYBLUE (1800 3650);
FORCEPROP 2 LAST CDS_LIB pure_quanta
J 0
(1750 3850);
PAINT MONO (1750 3850);
DISPLAY INVISIBLE (1750 3850);
FORCEPROP 1 LAST PATH I24
J 0
(1800 4000);
DISPLAY 0.978723 (1800 4000);
PAINT WHITE (1800 4000);
DISPLAY INVISIBLE (1800 4000);
FORCEPROP 1 LAST PART_NUMBER CH622KMEB02
J 0
(1800 3700);
DISPLAY 0.489362 (1800 3700);
PAINT SKYBLUE (1800 3700);
DISPLAY INVISIBLE (1800 3700);
FORCEADD Q_CAP..1
(2200 1075);
FORCEPROP 1 LAST LOCATION C3916
J 0
(2250 1175);
DISPLAY 0.489362 (2250 1175);
PAINT SKYBLUE (2250 1175);
FORCEPROP 2 LAST $SEC 1
J 0
(2250 1275);
DISPLAY 0.680851 (2250 1275);
PAINT MONO (2250 1275);
DISPLAY INVISIBLE (2250 1275);
FORCEPROP 2 LAST CDS_SEC 1
J 0
(2250 1275);
DISPLAY 1.021277 (2250 1275);
DISPLAY INVISIBLE (2250 1275);
FORCEPROP 1 LASTPIN (2200 1175) $PN 1
J 0
(2210 1155);
DISPLAY 0.489362 (2210 1155);
FORCEPROP 1 LASTPIN (2200 975) $PN 2
J 0
(2210 955);
DISPLAY 0.489362 (2210 955);
FORCEPROP 1 LAST MATERIAL X6S
J 0
(2250 975);
DISPLAY 0.489362 (2250 975);
PAINT SKYBLUE (2250 975);
FORCEPROP 1 LAST TOLERANCE 20%
J 0
(2250 1025);
DISPLAY 0.489362 (2250 1025);
PAINT SKYBLUE (2250 1025);
FORCEPROP 1 LAST VALUE 22UF
J 0
(2250 1125);
DISPLAY 0.489362 (2250 1125);
PAINT SKYBLUE (2250 1125);
FORCEPROP 1 LAST VOLTAGE 4V
J 0
(2250 1075);
DISPLAY 0.489362 (2250 1075);
PAINT SKYBLUE (2250 1075);
FORCEPROP 1 LAST PACK_TYPE C0402
J 0
(2250 875);
DISPLAY 0.489362 (2250 875);
PAINT SKYBLUE (2250 875);
FORCEPROP 2 LAST CDS_LIB pure_quanta
J 0
(2200 1075);
PAINT MONO (2200 1075);
DISPLAY INVISIBLE (2200 1075);
FORCEPROP 1 LAST PATH I25
J 0
(2250 1225);
DISPLAY 0.978723 (2250 1225);
PAINT WHITE (2250 1225);
DISPLAY INVISIBLE (2250 1225);
FORCEPROP 1 LAST PART_NUMBER CH622KMEB02
J 0
(2250 925);
DISPLAY 0.489362 (2250 925);
PAINT SKYBLUE (2250 925);
DISPLAY INVISIBLE (2250 925);
FORCEADD Q_CAP..1
(2200 1800);
FORCEPROP 1 LAST LOCATION C2441
J 0
(2250 1900);
DISPLAY 0.489362 (2250 1900);
PAINT SKYBLUE (2250 1900);
FORCEPROP 2 LAST $SEC 1
J 0
(2250 2000);
DISPLAY 0.680851 (2250 2000);
PAINT MONO (2250 2000);
DISPLAY INVISIBLE (2250 2000);
FORCEPROP 2 LAST CDS_SEC 1
J 0
(2250 2000);
DISPLAY 1.021277 (2250 2000);
DISPLAY INVISIBLE (2250 2000);
FORCEPROP 1 LASTPIN (2200 1900) $PN 1
J 0
(2210 1880);
DISPLAY 0.489362 (2210 1880);
FORCEPROP 1 LASTPIN (2200 1700) $PN 2
J 0
(2210 1680);
DISPLAY 0.489362 (2210 1680);
FORCEPROP 1 LAST MATERIAL X6S
J 0
(2250 1700);
DISPLAY 0.489362 (2250 1700);
PAINT SKYBLUE (2250 1700);
FORCEPROP 1 LAST TOLERANCE 20%
J 0
(2250 1750);
DISPLAY 0.489362 (2250 1750);
PAINT SKYBLUE (2250 1750);
FORCEPROP 1 LAST VALUE 22UF
J 0
(2250 1850);
DISPLAY 0.489362 (2250 1850);
PAINT SKYBLUE (2250 1850);
FORCEPROP 1 LAST VOLTAGE 4V
J 0
(2250 1800);
DISPLAY 0.489362 (2250 1800);
PAINT SKYBLUE (2250 1800);
FORCEPROP 1 LAST PACK_TYPE C0402
J 0
(2250 1600);
DISPLAY 0.489362 (2250 1600);
PAINT SKYBLUE (2250 1600);
FORCEPROP 2 LAST CDS_LIB pure_quanta
J 0
(2200 1800);
PAINT MONO (2200 1800);
DISPLAY INVISIBLE (2200 1800);
FORCEPROP 1 LAST PATH I26
J 0
(2250 1950);
DISPLAY 0.978723 (2250 1950);
PAINT WHITE (2250 1950);
DISPLAY INVISIBLE (2250 1950);
FORCEPROP 1 LAST PART_NUMBER CH622KMEB02
J 0
(2250 1650);
DISPLAY 0.489362 (2250 1650);
PAINT SKYBLUE (2250 1650);
DISPLAY INVISIBLE (2250 1650);
FORCEADD Q_CAP..1
(2650 1075);
FORCEPROP 1 LAST LOCATION C3917
J 0
(2700 1175);
DISPLAY 0.489362 (2700 1175);
PAINT SKYBLUE (2700 1175);
FORCEPROP 2 LAST $SEC 1
J 0
(2700 1275);
DISPLAY 0.680851 (2700 1275);
PAINT MONO (2700 1275);
DISPLAY INVISIBLE (2700 1275);
FORCEPROP 2 LAST CDS_SEC 1
J 0
(2700 1275);
DISPLAY 1.021277 (2700 1275);
DISPLAY INVISIBLE (2700 1275);
FORCEPROP 1 LASTPIN (2650 1175) $PN 1
J 0
(2660 1155);
DISPLAY 0.489362 (2660 1155);
FORCEPROP 1 LASTPIN (2650 975) $PN 2
J 0
(2660 955);
DISPLAY 0.489362 (2660 955);
FORCEPROP 1 LAST MATERIAL X6S
J 0
(2700 975);
DISPLAY 0.489362 (2700 975);
PAINT SKYBLUE (2700 975);
FORCEPROP 1 LAST TOLERANCE 20%
J 0
(2700 1025);
DISPLAY 0.489362 (2700 1025);
PAINT SKYBLUE (2700 1025);
FORCEPROP 1 LAST VALUE 22UF
J 0
(2700 1125);
DISPLAY 0.489362 (2700 1125);
PAINT SKYBLUE (2700 1125);
FORCEPROP 1 LAST VOLTAGE 4V
J 0
(2700 1075);
DISPLAY 0.489362 (2700 1075);
PAINT SKYBLUE (2700 1075);
FORCEPROP 1 LAST PACK_TYPE C0402
J 0
(2700 875);
DISPLAY 0.489362 (2700 875);
PAINT SKYBLUE (2700 875);
FORCEPROP 2 LAST CDS_LIB pure_quanta
J 0
(2650 1075);
PAINT MONO (2650 1075);
DISPLAY INVISIBLE (2650 1075);
FORCEPROP 1 LAST PATH I27
J 0
(2700 1225);
DISPLAY 0.978723 (2700 1225);
PAINT WHITE (2700 1225);
DISPLAY INVISIBLE (2700 1225);
FORCEPROP 1 LAST PART_NUMBER CH622KMEB02
J 0
(2700 925);
DISPLAY 0.489362 (2700 925);
PAINT SKYBLUE (2700 925);
DISPLAY INVISIBLE (2700 925);
FORCEADD Q_CAP..1
(2650 1800);
FORCEPROP 1 LAST LOCATION C2448
J 0
(2700 1900);
DISPLAY 0.489362 (2700 1900);
PAINT SKYBLUE (2700 1900);
FORCEPROP 2 LAST $SEC 1
J 0
(2700 2000);
DISPLAY 0.680851 (2700 2000);
PAINT MONO (2700 2000);
DISPLAY INVISIBLE (2700 2000);
FORCEPROP 2 LAST CDS_SEC 1
J 0
(2700 2000);
DISPLAY 1.021277 (2700 2000);
DISPLAY INVISIBLE (2700 2000);
FORCEPROP 1 LASTPIN (2650 1900) $PN 1
J 0
(2660 1880);
DISPLAY 0.489362 (2660 1880);
FORCEPROP 1 LASTPIN (2650 1700) $PN 2
J 0
(2660 1680);
DISPLAY 0.489362 (2660 1680);
FORCEPROP 1 LAST MATERIAL X6S
J 0
(2700 1700);
DISPLAY 0.489362 (2700 1700);
PAINT SKYBLUE (2700 1700);
FORCEPROP 1 LAST TOLERANCE 20%
J 0
(2700 1750);
DISPLAY 0.489362 (2700 1750);
PAINT SKYBLUE (2700 1750);
FORCEPROP 1 LAST VALUE 22UF
J 0
(2700 1850);
DISPLAY 0.489362 (2700 1850);
PAINT SKYBLUE (2700 1850);
FORCEPROP 1 LAST VOLTAGE 4V
J 0
(2700 1800);
DISPLAY 0.489362 (2700 1800);
PAINT SKYBLUE (2700 1800);
FORCEPROP 1 LAST PACK_TYPE C0402
J 0
(2700 1600);
DISPLAY 0.489362 (2700 1600);
PAINT SKYBLUE (2700 1600);
FORCEPROP 2 LAST CDS_LIB pure_quanta
J 0
(2650 1800);
PAINT MONO (2650 1800);
DISPLAY INVISIBLE (2650 1800);
FORCEPROP 1 LAST PATH I28
J 0
(2700 1950);
DISPLAY 0.978723 (2700 1950);
PAINT WHITE (2700 1950);
DISPLAY INVISIBLE (2700 1950);
FORCEPROP 1 LAST PART_NUMBER CH622KMEB02
J 0
(2700 1650);
DISPLAY 0.489362 (2700 1650);
PAINT SKYBLUE (2700 1650);
DISPLAY INVISIBLE (2700 1650);
FORCEADD Q_CAP..1
(3100 1800);
FORCEPROP 1 LAST LOCATION C2455
J 0
(3150 1900);
DISPLAY 0.489362 (3150 1900);
PAINT SKYBLUE (3150 1900);
FORCEPROP 2 LAST $SEC 1
J 0
(3150 2000);
DISPLAY 0.680851 (3150 2000);
PAINT MONO (3150 2000);
DISPLAY INVISIBLE (3150 2000);
FORCEPROP 2 LAST CDS_SEC 1
J 0
(3150 2000);
DISPLAY 1.021277 (3150 2000);
DISPLAY INVISIBLE (3150 2000);
FORCEPROP 1 LASTPIN (3100 1900) $PN 1
J 0
(3110 1880);
DISPLAY 0.489362 (3110 1880);
FORCEPROP 1 LASTPIN (3100 1700) $PN 2
J 0
(3110 1680);
DISPLAY 0.489362 (3110 1680);
FORCEPROP 1 LAST MATERIAL X6S
J 0
(3150 1700);
DISPLAY 0.489362 (3150 1700);
PAINT SKYBLUE (3150 1700);
FORCEPROP 1 LAST TOLERANCE 20%
J 0
(3150 1750);
DISPLAY 0.489362 (3150 1750);
PAINT SKYBLUE (3150 1750);
FORCEPROP 1 LAST VALUE 22UF
J 0
(3150 1850);
DISPLAY 0.489362 (3150 1850);
PAINT SKYBLUE (3150 1850);
FORCEPROP 1 LAST VOLTAGE 4V
J 0
(3150 1800);
DISPLAY 0.489362 (3150 1800);
PAINT SKYBLUE (3150 1800);
FORCEPROP 1 LAST PACK_TYPE C0402
J 0
(3150 1600);
DISPLAY 0.489362 (3150 1600);
PAINT SKYBLUE (3150 1600);
FORCEPROP 2 LAST CDS_LIB pure_quanta
J 0
(3100 1800);
PAINT MONO (3100 1800);
DISPLAY INVISIBLE (3100 1800);
FORCEPROP 1 LAST PATH I29
J 0
(3150 1950);
DISPLAY 0.978723 (3150 1950);
PAINT WHITE (3150 1950);
DISPLAY INVISIBLE (3150 1950);
FORCEPROP 1 LAST PART_NUMBER CH622KMEB02
J 0
(3150 1650);
DISPLAY 0.489362 (3150 1650);
PAINT SKYBLUE (3150 1650);
DISPLAY INVISIBLE (3150 1650);
FORCEADD Q_CAP..1
(400 1800);
FORCEPROP 1 LAST LOCATION C2413
J 0
(450 1900);
DISPLAY 0.489362 (450 1900);
PAINT SKYBLUE (450 1900);
FORCEPROP 2 LAST $SEC 1
J 0
(450 2000);
DISPLAY 0.680851 (450 2000);
PAINT MONO (450 2000);
DISPLAY INVISIBLE (450 2000);
FORCEPROP 2 LAST CDS_SEC 1
J 0
(450 2000);
DISPLAY 1.021277 (450 2000);
DISPLAY INVISIBLE (450 2000);
FORCEPROP 1 LASTPIN (400 1900) $PN 1
J 0
(410 1880);
DISPLAY 0.489362 (410 1880);
FORCEPROP 1 LASTPIN (400 1700) $PN 2
J 0
(410 1680);
DISPLAY 0.489362 (410 1680);
FORCEPROP 1 LAST MATERIAL X6S
J 0
(450 1700);
DISPLAY 0.489362 (450 1700);
PAINT SKYBLUE (450 1700);
FORCEPROP 1 LAST TOLERANCE 20%
J 0
(450 1750);
DISPLAY 0.489362 (450 1750);
PAINT SKYBLUE (450 1750);
FORCEPROP 1 LAST VALUE 22UF
J 0
(450 1850);
DISPLAY 0.489362 (450 1850);
PAINT SKYBLUE (450 1850);
FORCEPROP 1 LAST VOLTAGE 4V
J 0
(450 1800);
DISPLAY 0.489362 (450 1800);
PAINT SKYBLUE (450 1800);
FORCEPROP 1 LAST PACK_TYPE C0402
J 0
(450 1600);
DISPLAY 0.489362 (450 1600);
PAINT SKYBLUE (450 1600);
FORCEPROP 2 LAST CDS_LIB pure_quanta
J 0
(400 1800);
PAINT MONO (400 1800);
DISPLAY INVISIBLE (400 1800);
FORCEPROP 1 LAST PATH I3
J 0
(450 1950);
DISPLAY 0.978723 (450 1950);
PAINT WHITE (450 1950);
DISPLAY INVISIBLE (450 1950);
FORCEPROP 1 LAST PART_NUMBER CH622KMEB02
J 0
(450 1650);
DISPLAY 0.489362 (450 1650);
PAINT SKYBLUE (450 1650);
DISPLAY INVISIBLE (450 1650);
FORCEADD Q_CAP..1
(3100 1075);
FORCEPROP 1 LAST LOCATION C3918
J 0
(3150 1175);
DISPLAY 0.489362 (3150 1175);
PAINT SKYBLUE (3150 1175);
FORCEPROP 2 LAST $SEC 1
J 0
(3150 1275);
DISPLAY 0.680851 (3150 1275);
PAINT MONO (3150 1275);
DISPLAY INVISIBLE (3150 1275);
FORCEPROP 2 LAST CDS_SEC 1
J 0
(3150 1275);
DISPLAY 1.021277 (3150 1275);
DISPLAY INVISIBLE (3150 1275);
FORCEPROP 1 LASTPIN (3100 1175) $PN 1
J 0
(3110 1155);
DISPLAY 0.489362 (3110 1155);
FORCEPROP 1 LASTPIN (3100 975) $PN 2
J 0
(3110 955);
DISPLAY 0.489362 (3110 955);
FORCEPROP 1 LAST MATERIAL X6S
J 0
(3150 975);
DISPLAY 0.489362 (3150 975);
PAINT SKYBLUE (3150 975);
FORCEPROP 1 LAST TOLERANCE 20%
J 0
(3150 1025);
DISPLAY 0.489362 (3150 1025);
PAINT SKYBLUE (3150 1025);
FORCEPROP 1 LAST VALUE 22UF
J 0
(3150 1125);
DISPLAY 0.489362 (3150 1125);
PAINT SKYBLUE (3150 1125);
FORCEPROP 1 LAST VOLTAGE 4V
J 0
(3150 1075);
DISPLAY 0.489362 (3150 1075);
PAINT SKYBLUE (3150 1075);
FORCEPROP 1 LAST PACK_TYPE C0402
J 0
(3150 875);
DISPLAY 0.489362 (3150 875);
PAINT SKYBLUE (3150 875);
FORCEPROP 2 LAST CDS_LIB pure_quanta
J 0
(3100 1075);
PAINT MONO (3100 1075);
DISPLAY INVISIBLE (3100 1075);
FORCEPROP 1 LAST PATH I30
J 0
(3150 1225);
DISPLAY 0.978723 (3150 1225);
PAINT WHITE (3150 1225);
DISPLAY INVISIBLE (3150 1225);
FORCEPROP 1 LAST PART_NUMBER CH622KMEB02
J 0
(3150 925);
DISPLAY 0.489362 (3150 925);
PAINT SKYBLUE (3150 925);
DISPLAY INVISIBLE (3150 925);
FORCEADD UNIVERSAL_GND..1
(3100 700);
FORCEPROP 3 LASTPIN (3100 750) SIG_NAME GND\g
J 0
(3110 760);
DISPLAY 0.659574 (3110 760);
PAINT MONO (3110 760);
DISPLAY INVISIBLE (3110 760);
FORCEPROP 2 LAST CDS_LIB pure_quanta_power
J 0
(3100 700);
PAINT MONO (3100 700);
DISPLAY INVISIBLE (3100 700);
FORCEPROP 1 LAST HDL_POWER GND
J 1
(3125 625);
DISPLAY 0.872340 (3125 625);
PAINT GREEN (3125 625);
DISPLAY INVISIBLE (3125 625);
FORCEPROP 1 LAST PATH I31
J 0
(3175 700);
DISPLAY 0.872340 (3175 700);
PAINT AQUA (3175 700);
DISPLAY INVISIBLE (3175 700);
FORCEADD Q_CAP..1
(3550 1800);
FORCEPROP 1 LAST LOCATION C2462
J 0
(3600 1900);
DISPLAY 0.489362 (3600 1900);
PAINT SKYBLUE (3600 1900);
FORCEPROP 2 LAST $SEC 1
J 0
(3600 2000);
DISPLAY 0.680851 (3600 2000);
PAINT MONO (3600 2000);
DISPLAY INVISIBLE (3600 2000);
FORCEPROP 2 LAST CDS_SEC 1
J 0
(3600 2000);
DISPLAY 1.021277 (3600 2000);
DISPLAY INVISIBLE (3600 2000);
FORCEPROP 1 LASTPIN (3550 1900) $PN 1
J 0
(3560 1880);
DISPLAY 0.489362 (3560 1880);
FORCEPROP 1 LASTPIN (3550 1700) $PN 2
J 0
(3560 1680);
DISPLAY 0.489362 (3560 1680);
FORCEPROP 1 LAST MATERIAL X6S
J 0
(3600 1700);
DISPLAY 0.489362 (3600 1700);
PAINT SKYBLUE (3600 1700);
FORCEPROP 1 LAST TOLERANCE 20%
J 0
(3600 1750);
DISPLAY 0.489362 (3600 1750);
PAINT SKYBLUE (3600 1750);
FORCEPROP 1 LAST VALUE 22UF
J 0
(3600 1850);
DISPLAY 0.489362 (3600 1850);
PAINT SKYBLUE (3600 1850);
FORCEPROP 1 LAST VOLTAGE 4V
J 0
(3600 1800);
DISPLAY 0.489362 (3600 1800);
PAINT SKYBLUE (3600 1800);
FORCEPROP 1 LAST PACK_TYPE C0402
J 0
(3600 1600);
DISPLAY 0.489362 (3600 1600);
PAINT SKYBLUE (3600 1600);
FORCEPROP 2 LAST CDS_LIB pure_quanta
J 0
(3550 1800);
PAINT MONO (3550 1800);
DISPLAY INVISIBLE (3550 1800);
FORCEPROP 1 LAST PATH I32
J 0
(3600 1950);
DISPLAY 0.978723 (3600 1950);
PAINT WHITE (3600 1950);
DISPLAY INVISIBLE (3600 1950);
FORCEPROP 1 LAST PART_NUMBER CH622KMEB02
J 0
(3600 1650);
DISPLAY 0.489362 (3600 1650);
PAINT SKYBLUE (3600 1650);
DISPLAY INVISIBLE (3600 1650);
FORCEADD Q_CAP..1
(4000 1800);
FORCEPROP 1 LAST LOCATION C2469
J 0
(4050 1900);
DISPLAY 0.489362 (4050 1900);
PAINT SKYBLUE (4050 1900);
FORCEPROP 2 LAST $SEC 1
J 0
(4050 2000);
DISPLAY 0.680851 (4050 2000);
PAINT MONO (4050 2000);
DISPLAY INVISIBLE (4050 2000);
FORCEPROP 2 LAST CDS_SEC 1
J 0
(4050 2000);
DISPLAY 1.021277 (4050 2000);
DISPLAY INVISIBLE (4050 2000);
FORCEPROP 1 LASTPIN (4000 1900) $PN 1
J 0
(4010 1880);
DISPLAY 0.489362 (4010 1880);
FORCEPROP 1 LASTPIN (4000 1700) $PN 2
J 0
(4010 1680);
DISPLAY 0.489362 (4010 1680);
FORCEPROP 1 LAST MATERIAL X6S
J 0
(4050 1700);
DISPLAY 0.489362 (4050 1700);
PAINT SKYBLUE (4050 1700);
FORCEPROP 1 LAST TOLERANCE 20%
J 0
(4050 1750);
DISPLAY 0.489362 (4050 1750);
PAINT SKYBLUE (4050 1750);
FORCEPROP 1 LAST VALUE 22UF
J 0
(4050 1850);
DISPLAY 0.489362 (4050 1850);
PAINT SKYBLUE (4050 1850);
FORCEPROP 1 LAST VOLTAGE 4V
J 0
(4050 1800);
DISPLAY 0.489362 (4050 1800);
PAINT SKYBLUE (4050 1800);
FORCEPROP 1 LAST PACK_TYPE C0402
J 0
(4050 1600);
DISPLAY 0.489362 (4050 1600);
PAINT SKYBLUE (4050 1600);
FORCEPROP 2 LAST CDS_LIB pure_quanta
J 0
(4000 1800);
PAINT MONO (4000 1800);
DISPLAY INVISIBLE (4000 1800);
FORCEPROP 1 LAST PATH I33
J 0
(4050 1950);
DISPLAY 0.978723 (4050 1950);
PAINT WHITE (4050 1950);
DISPLAY INVISIBLE (4050 1950);
FORCEPROP 1 LAST PART_NUMBER CH622KMEB02
J 0
(4050 1650);
DISPLAY 0.489362 (4050 1650);
PAINT SKYBLUE (4050 1650);
DISPLAY INVISIBLE (4050 1650);
FORCEADD Q_CAP..1
(2200 2475);
FORCEPROP 1 LAST LOCATION C2440
J 0
(2250 2575);
DISPLAY 0.489362 (2250 2575);
PAINT SKYBLUE (2250 2575);
FORCEPROP 2 LAST $SEC 1
J 0
(2250 2675);
DISPLAY 0.680851 (2250 2675);
PAINT MONO (2250 2675);
DISPLAY INVISIBLE (2250 2675);
FORCEPROP 2 LAST CDS_SEC 1
J 0
(2250 2675);
DISPLAY 1.021277 (2250 2675);
DISPLAY INVISIBLE (2250 2675);
FORCEPROP 1 LASTPIN (2200 2575) $PN 1
J 0
(2210 2555);
DISPLAY 0.489362 (2210 2555);
FORCEPROP 1 LASTPIN (2200 2375) $PN 2
J 0
(2210 2355);
DISPLAY 0.489362 (2210 2355);
FORCEPROP 1 LAST MATERIAL X6S
J 0
(2250 2375);
DISPLAY 0.489362 (2250 2375);
PAINT SKYBLUE (2250 2375);
FORCEPROP 1 LAST TOLERANCE 20%
J 0
(2250 2425);
DISPLAY 0.489362 (2250 2425);
PAINT SKYBLUE (2250 2425);
FORCEPROP 1 LAST VALUE 22UF
J 0
(2250 2525);
DISPLAY 0.489362 (2250 2525);
PAINT SKYBLUE (2250 2525);
FORCEPROP 1 LAST VOLTAGE 4V
J 0
(2250 2475);
DISPLAY 0.489362 (2250 2475);
PAINT SKYBLUE (2250 2475);
FORCEPROP 1 LAST PACK_TYPE C0402
J 0
(2250 2275);
DISPLAY 0.489362 (2250 2275);
PAINT SKYBLUE (2250 2275);
FORCEPROP 2 LAST CDS_LIB pure_quanta
J 0
(2200 2475);
PAINT MONO (2200 2475);
DISPLAY INVISIBLE (2200 2475);
FORCEPROP 1 LAST PATH I34
J 0
(2250 2625);
DISPLAY 0.978723 (2250 2625);
PAINT WHITE (2250 2625);
DISPLAY INVISIBLE (2250 2625);
FORCEPROP 1 LAST PART_NUMBER CH622KMEB02
J 0
(2250 2325);
DISPLAY 0.489362 (2250 2325);
PAINT SKYBLUE (2250 2325);
DISPLAY INVISIBLE (2250 2325);
FORCEADD Q_CAP..1
(2650 2475);
FORCEPROP 1 LAST LOCATION C2447
J 0
(2700 2575);
DISPLAY 0.489362 (2700 2575);
PAINT SKYBLUE (2700 2575);
FORCEPROP 2 LAST $SEC 1
J 0
(2700 2675);
DISPLAY 0.680851 (2700 2675);
PAINT MONO (2700 2675);
DISPLAY INVISIBLE (2700 2675);
FORCEPROP 2 LAST CDS_SEC 1
J 0
(2700 2675);
DISPLAY 1.021277 (2700 2675);
DISPLAY INVISIBLE (2700 2675);
FORCEPROP 1 LASTPIN (2650 2575) $PN 1
J 0
(2660 2555);
DISPLAY 0.489362 (2660 2555);
FORCEPROP 1 LASTPIN (2650 2375) $PN 2
J 0
(2660 2355);
DISPLAY 0.489362 (2660 2355);
FORCEPROP 1 LAST MATERIAL X6S
J 0
(2700 2375);
DISPLAY 0.489362 (2700 2375);
PAINT SKYBLUE (2700 2375);
FORCEPROP 1 LAST TOLERANCE 20%
J 0
(2700 2425);
DISPLAY 0.489362 (2700 2425);
PAINT SKYBLUE (2700 2425);
FORCEPROP 1 LAST VALUE 22UF
J 0
(2700 2525);
DISPLAY 0.489362 (2700 2525);
PAINT SKYBLUE (2700 2525);
FORCEPROP 1 LAST VOLTAGE 4V
J 0
(2700 2475);
DISPLAY 0.489362 (2700 2475);
PAINT SKYBLUE (2700 2475);
FORCEPROP 1 LAST PACK_TYPE C0402
J 0
(2700 2275);
DISPLAY 0.489362 (2700 2275);
PAINT SKYBLUE (2700 2275);
FORCEPROP 2 LAST CDS_LIB pure_quanta
J 0
(2650 2475);
PAINT MONO (2650 2475);
DISPLAY INVISIBLE (2650 2475);
FORCEPROP 1 LAST PATH I35
J 0
(2700 2625);
DISPLAY 0.978723 (2700 2625);
PAINT WHITE (2700 2625);
DISPLAY INVISIBLE (2700 2625);
FORCEPROP 1 LAST PART_NUMBER CH622KMEB02
J 0
(2700 2325);
DISPLAY 0.489362 (2700 2325);
PAINT SKYBLUE (2700 2325);
DISPLAY INVISIBLE (2700 2325);
FORCEADD Q_CAP..1
(2200 3150);
FORCEPROP 1 LAST LOCATION C2439
J 0
(2250 3250);
DISPLAY 0.489362 (2250 3250);
PAINT SKYBLUE (2250 3250);
FORCEPROP 2 LAST $SEC 1
J 0
(2250 3350);
DISPLAY 0.680851 (2250 3350);
PAINT MONO (2250 3350);
DISPLAY INVISIBLE (2250 3350);
FORCEPROP 2 LAST CDS_SEC 1
J 0
(2250 3350);
DISPLAY 1.021277 (2250 3350);
DISPLAY INVISIBLE (2250 3350);
FORCEPROP 1 LASTPIN (2200 3250) $PN 1
J 0
(2210 3230);
DISPLAY 0.489362 (2210 3230);
FORCEPROP 1 LASTPIN (2200 3050) $PN 2
J 0
(2210 3030);
DISPLAY 0.489362 (2210 3030);
FORCEPROP 1 LAST MATERIAL X6S
J 0
(2250 3050);
DISPLAY 0.489362 (2250 3050);
PAINT SKYBLUE (2250 3050);
FORCEPROP 1 LAST TOLERANCE 20%
J 0
(2250 3100);
DISPLAY 0.489362 (2250 3100);
PAINT SKYBLUE (2250 3100);
FORCEPROP 1 LAST VALUE 22UF
J 0
(2250 3200);
DISPLAY 0.489362 (2250 3200);
PAINT SKYBLUE (2250 3200);
FORCEPROP 1 LAST VOLTAGE 4V
J 0
(2250 3150);
DISPLAY 0.489362 (2250 3150);
PAINT SKYBLUE (2250 3150);
FORCEPROP 1 LAST PACK_TYPE C0402
J 0
(2250 2950);
DISPLAY 0.489362 (2250 2950);
PAINT SKYBLUE (2250 2950);
FORCEPROP 2 LAST CDS_LIB pure_quanta
J 0
(2200 3150);
PAINT MONO (2200 3150);
DISPLAY INVISIBLE (2200 3150);
FORCEPROP 1 LAST PATH I36
J 0
(2250 3300);
DISPLAY 0.978723 (2250 3300);
PAINT WHITE (2250 3300);
DISPLAY INVISIBLE (2250 3300);
FORCEPROP 1 LAST PART_NUMBER CH622KMEB02
J 0
(2250 3000);
DISPLAY 0.489362 (2250 3000);
PAINT SKYBLUE (2250 3000);
DISPLAY INVISIBLE (2250 3000);
FORCEADD Q_CAP..1
(2200 3850);
FORCEPROP 1 LAST LOCATION C2438
J 0
(2250 3950);
DISPLAY 0.489362 (2250 3950);
PAINT SKYBLUE (2250 3950);
FORCEPROP 2 LAST $SEC 1
J 0
(2250 4050);
DISPLAY 0.680851 (2250 4050);
PAINT MONO (2250 4050);
DISPLAY INVISIBLE (2250 4050);
FORCEPROP 2 LAST CDS_SEC 1
J 0
(2250 4050);
DISPLAY 1.021277 (2250 4050);
DISPLAY INVISIBLE (2250 4050);
FORCEPROP 1 LASTPIN (2200 3950) $PN 1
J 0
(2210 3930);
DISPLAY 0.489362 (2210 3930);
FORCEPROP 1 LASTPIN (2200 3750) $PN 2
J 0
(2210 3730);
DISPLAY 0.489362 (2210 3730);
FORCEPROP 1 LAST MATERIAL X6S
J 0
(2250 3750);
DISPLAY 0.489362 (2250 3750);
PAINT SKYBLUE (2250 3750);
FORCEPROP 1 LAST TOLERANCE 20%
J 0
(2250 3800);
DISPLAY 0.489362 (2250 3800);
PAINT SKYBLUE (2250 3800);
FORCEPROP 1 LAST VALUE 22UF
J 0
(2250 3900);
DISPLAY 0.489362 (2250 3900);
PAINT SKYBLUE (2250 3900);
FORCEPROP 1 LAST VOLTAGE 4V
J 0
(2250 3850);
DISPLAY 0.489362 (2250 3850);
PAINT SKYBLUE (2250 3850);
FORCEPROP 1 LAST PACK_TYPE C0402
J 0
(2250 3650);
DISPLAY 0.489362 (2250 3650);
PAINT SKYBLUE (2250 3650);
FORCEPROP 2 LAST CDS_LIB pure_quanta
J 0
(2200 3850);
PAINT MONO (2200 3850);
DISPLAY INVISIBLE (2200 3850);
FORCEPROP 1 LAST PATH I37
J 0
(2250 4000);
DISPLAY 0.978723 (2250 4000);
PAINT WHITE (2250 4000);
DISPLAY INVISIBLE (2250 4000);
FORCEPROP 1 LAST PART_NUMBER CH622KMEB02
J 0
(2250 3700);
DISPLAY 0.489362 (2250 3700);
PAINT SKYBLUE (2250 3700);
DISPLAY INVISIBLE (2250 3700);
FORCEADD Q_CAP..1
(2650 3150);
FORCEPROP 1 LAST LOCATION C2446
J 0
(2700 3250);
DISPLAY 0.489362 (2700 3250);
PAINT SKYBLUE (2700 3250);
FORCEPROP 2 LAST $SEC 1
J 0
(2700 3350);
DISPLAY 0.680851 (2700 3350);
PAINT MONO (2700 3350);
DISPLAY INVISIBLE (2700 3350);
FORCEPROP 2 LAST CDS_SEC 1
J 0
(2700 3350);
DISPLAY 1.021277 (2700 3350);
DISPLAY INVISIBLE (2700 3350);
FORCEPROP 1 LASTPIN (2650 3250) $PN 1
J 0
(2660 3230);
DISPLAY 0.489362 (2660 3230);
FORCEPROP 1 LASTPIN (2650 3050) $PN 2
J 0
(2660 3030);
DISPLAY 0.489362 (2660 3030);
FORCEPROP 1 LAST MATERIAL X6S
J 0
(2700 3050);
DISPLAY 0.489362 (2700 3050);
PAINT SKYBLUE (2700 3050);
FORCEPROP 1 LAST TOLERANCE 20%
J 0
(2700 3100);
DISPLAY 0.489362 (2700 3100);
PAINT SKYBLUE (2700 3100);
FORCEPROP 1 LAST VALUE 22UF
J 0
(2700 3200);
DISPLAY 0.489362 (2700 3200);
PAINT SKYBLUE (2700 3200);
FORCEPROP 1 LAST VOLTAGE 4V
J 0
(2700 3150);
DISPLAY 0.489362 (2700 3150);
PAINT SKYBLUE (2700 3150);
FORCEPROP 1 LAST PACK_TYPE C0402
J 0
(2700 2950);
DISPLAY 0.489362 (2700 2950);
PAINT SKYBLUE (2700 2950);
FORCEPROP 2 LAST CDS_LIB pure_quanta
J 0
(2650 3150);
PAINT MONO (2650 3150);
DISPLAY INVISIBLE (2650 3150);
FORCEPROP 1 LAST PATH I38
J 0
(2700 3300);
DISPLAY 0.978723 (2700 3300);
PAINT WHITE (2700 3300);
DISPLAY INVISIBLE (2700 3300);
FORCEPROP 1 LAST PART_NUMBER CH622KMEB02
J 0
(2700 3000);
DISPLAY 0.489362 (2700 3000);
PAINT SKYBLUE (2700 3000);
DISPLAY INVISIBLE (2700 3000);
FORCEADD Q_CAP..1
(2650 3850);
FORCEPROP 1 LAST LOCATION C2445
J 0
(2700 3950);
DISPLAY 0.489362 (2700 3950);
PAINT SKYBLUE (2700 3950);
FORCEPROP 2 LAST $SEC 1
J 0
(2700 4050);
DISPLAY 0.680851 (2700 4050);
PAINT MONO (2700 4050);
DISPLAY INVISIBLE (2700 4050);
FORCEPROP 2 LAST CDS_SEC 1
J 0
(2700 4050);
DISPLAY 1.021277 (2700 4050);
DISPLAY INVISIBLE (2700 4050);
FORCEPROP 1 LASTPIN (2650 3950) $PN 1
J 0
(2660 3930);
DISPLAY 0.489362 (2660 3930);
FORCEPROP 1 LASTPIN (2650 3750) $PN 2
J 0
(2660 3730);
DISPLAY 0.489362 (2660 3730);
FORCEPROP 1 LAST MATERIAL X6S
J 0
(2700 3750);
DISPLAY 0.489362 (2700 3750);
PAINT SKYBLUE (2700 3750);
FORCEPROP 1 LAST TOLERANCE 20%
J 0
(2700 3800);
DISPLAY 0.489362 (2700 3800);
PAINT SKYBLUE (2700 3800);
FORCEPROP 1 LAST VALUE 22UF
J 0
(2700 3900);
DISPLAY 0.489362 (2700 3900);
PAINT SKYBLUE (2700 3900);
FORCEPROP 1 LAST VOLTAGE 4V
J 0
(2700 3850);
DISPLAY 0.489362 (2700 3850);
PAINT SKYBLUE (2700 3850);
FORCEPROP 1 LAST PACK_TYPE C0402
J 0
(2700 3650);
DISPLAY 0.489362 (2700 3650);
PAINT SKYBLUE (2700 3650);
FORCEPROP 2 LAST CDS_LIB pure_quanta
J 0
(2650 3850);
PAINT MONO (2650 3850);
DISPLAY INVISIBLE (2650 3850);
FORCEPROP 1 LAST PATH I39
J 0
(2700 4000);
DISPLAY 0.978723 (2700 4000);
PAINT WHITE (2700 4000);
DISPLAY INVISIBLE (2700 4000);
FORCEPROP 1 LAST PART_NUMBER CH622KMEB02
J 0
(2700 3700);
DISPLAY 0.489362 (2700 3700);
PAINT SKYBLUE (2700 3700);
DISPLAY INVISIBLE (2700 3700);
FORCEADD Q_CAP..1
(850 1075);
FORCEPROP 1 LAST LOCATION C3913
J 0
(900 1175);
DISPLAY 0.489362 (900 1175);
PAINT SKYBLUE (900 1175);
FORCEPROP 2 LAST $SEC 1
J 0
(900 1275);
DISPLAY 0.680851 (900 1275);
PAINT MONO (900 1275);
DISPLAY INVISIBLE (900 1275);
FORCEPROP 2 LAST CDS_SEC 1
J 0
(900 1275);
DISPLAY 1.021277 (900 1275);
DISPLAY INVISIBLE (900 1275);
FORCEPROP 1 LASTPIN (850 1175) $PN 1
J 0
(860 1155);
DISPLAY 0.489362 (860 1155);
FORCEPROP 1 LASTPIN (850 975) $PN 2
J 0
(860 955);
DISPLAY 0.489362 (860 955);
FORCEPROP 1 LAST MATERIAL X6S
J 0
(900 975);
DISPLAY 0.489362 (900 975);
PAINT SKYBLUE (900 975);
FORCEPROP 1 LAST TOLERANCE 20%
J 0
(900 1025);
DISPLAY 0.489362 (900 1025);
PAINT SKYBLUE (900 1025);
FORCEPROP 1 LAST VALUE 22UF
J 0
(900 1125);
DISPLAY 0.489362 (900 1125);
PAINT SKYBLUE (900 1125);
FORCEPROP 1 LAST VOLTAGE 4V
J 0
(900 1075);
DISPLAY 0.489362 (900 1075);
PAINT SKYBLUE (900 1075);
FORCEPROP 1 LAST PACK_TYPE C0402
J 0
(900 875);
DISPLAY 0.489362 (900 875);
PAINT SKYBLUE (900 875);
FORCEPROP 2 LAST CDS_LIB pure_quanta
J 0
(850 1075);
PAINT MONO (850 1075);
DISPLAY INVISIBLE (850 1075);
FORCEPROP 1 LAST PATH I4
J 0
(900 1225);
DISPLAY 0.978723 (900 1225);
PAINT WHITE (900 1225);
DISPLAY INVISIBLE (900 1225);
FORCEPROP 1 LAST PART_NUMBER CH622KMEB02
J 0
(900 925);
DISPLAY 0.489362 (900 925);
PAINT SKYBLUE (900 925);
DISPLAY INVISIBLE (900 925);
FORCEADD Q_CAP..1
(3100 3850);
FORCEPROP 1 LAST LOCATION C2452
J 0
(3150 3950);
DISPLAY 0.489362 (3150 3950);
PAINT SKYBLUE (3150 3950);
FORCEPROP 2 LAST $SEC 1
J 0
(3150 4050);
DISPLAY 0.680851 (3150 4050);
PAINT MONO (3150 4050);
DISPLAY INVISIBLE (3150 4050);
FORCEPROP 2 LAST CDS_SEC 1
J 0
(3150 4050);
DISPLAY 1.021277 (3150 4050);
DISPLAY INVISIBLE (3150 4050);
FORCEPROP 1 LASTPIN (3100 3950) $PN 1
J 0
(3110 3930);
DISPLAY 0.489362 (3110 3930);
FORCEPROP 1 LASTPIN (3100 3750) $PN 2
J 0
(3110 3730);
DISPLAY 0.489362 (3110 3730);
FORCEPROP 1 LAST MATERIAL X6S
J 0
(3150 3750);
DISPLAY 0.489362 (3150 3750);
PAINT SKYBLUE (3150 3750);
FORCEPROP 1 LAST TOLERANCE 20%
J 0
(3150 3800);
DISPLAY 0.489362 (3150 3800);
PAINT SKYBLUE (3150 3800);
FORCEPROP 1 LAST VALUE 22UF
J 0
(3150 3900);
DISPLAY 0.489362 (3150 3900);
PAINT SKYBLUE (3150 3900);
FORCEPROP 1 LAST VOLTAGE 4V
J 0
(3150 3850);
DISPLAY 0.489362 (3150 3850);
PAINT SKYBLUE (3150 3850);
FORCEPROP 1 LAST PACK_TYPE C0402
J 0
(3150 3650);
DISPLAY 0.489362 (3150 3650);
PAINT SKYBLUE (3150 3650);
FORCEPROP 2 LAST CDS_LIB pure_quanta
J 0
(3100 3850);
PAINT MONO (3100 3850);
DISPLAY INVISIBLE (3100 3850);
FORCEPROP 1 LAST PATH I40
J 0
(3150 4000);
DISPLAY 0.978723 (3150 4000);
PAINT WHITE (3150 4000);
DISPLAY INVISIBLE (3150 4000);
FORCEPROP 1 LAST PART_NUMBER CH622KMEB02
J 0
(3150 3700);
DISPLAY 0.489362 (3150 3700);
PAINT SKYBLUE (3150 3700);
DISPLAY INVISIBLE (3150 3700);
FORCEADD Q_CAP..1
(3100 3150);
FORCEPROP 1 LAST LOCATION C2453
J 0
(3150 3250);
DISPLAY 0.489362 (3150 3250);
PAINT SKYBLUE (3150 3250);
FORCEPROP 2 LAST $SEC 1
J 0
(3150 3350);
DISPLAY 0.680851 (3150 3350);
PAINT MONO (3150 3350);
DISPLAY INVISIBLE (3150 3350);
FORCEPROP 2 LAST CDS_SEC 1
J 0
(3150 3350);
DISPLAY 1.021277 (3150 3350);
DISPLAY INVISIBLE (3150 3350);
FORCEPROP 1 LASTPIN (3100 3250) $PN 1
J 0
(3110 3230);
DISPLAY 0.489362 (3110 3230);
FORCEPROP 1 LASTPIN (3100 3050) $PN 2
J 0
(3110 3030);
DISPLAY 0.489362 (3110 3030);
FORCEPROP 1 LAST MATERIAL X6S
J 0
(3150 3050);
DISPLAY 0.489362 (3150 3050);
PAINT SKYBLUE (3150 3050);
FORCEPROP 1 LAST TOLERANCE 20%
J 0
(3150 3100);
DISPLAY 0.489362 (3150 3100);
PAINT SKYBLUE (3150 3100);
FORCEPROP 1 LAST VALUE 22UF
J 0
(3150 3200);
DISPLAY 0.489362 (3150 3200);
PAINT SKYBLUE (3150 3200);
FORCEPROP 1 LAST VOLTAGE 4V
J 0
(3150 3150);
DISPLAY 0.489362 (3150 3150);
PAINT SKYBLUE (3150 3150);
FORCEPROP 1 LAST PACK_TYPE C0402
J 0
(3150 2950);
DISPLAY 0.489362 (3150 2950);
PAINT SKYBLUE (3150 2950);
FORCEPROP 2 LAST CDS_LIB pure_quanta
J 0
(3100 3150);
PAINT MONO (3100 3150);
DISPLAY INVISIBLE (3100 3150);
FORCEPROP 1 LAST PATH I41
J 0
(3150 3300);
DISPLAY 0.978723 (3150 3300);
PAINT WHITE (3150 3300);
DISPLAY INVISIBLE (3150 3300);
FORCEPROP 1 LAST PART_NUMBER CH622KMEB02
J 0
(3150 3000);
DISPLAY 0.489362 (3150 3000);
PAINT SKYBLUE (3150 3000);
DISPLAY INVISIBLE (3150 3000);
FORCEADD Q_CAP..1
(3100 2475);
FORCEPROP 1 LAST LOCATION C2454
J 0
(3150 2575);
DISPLAY 0.489362 (3150 2575);
PAINT SKYBLUE (3150 2575);
FORCEPROP 2 LAST $SEC 1
J 0
(3150 2675);
DISPLAY 0.680851 (3150 2675);
PAINT MONO (3150 2675);
DISPLAY INVISIBLE (3150 2675);
FORCEPROP 2 LAST CDS_SEC 1
J 0
(3150 2675);
DISPLAY 1.021277 (3150 2675);
DISPLAY INVISIBLE (3150 2675);
FORCEPROP 1 LASTPIN (3100 2575) $PN 1
J 0
(3110 2555);
DISPLAY 0.489362 (3110 2555);
FORCEPROP 1 LASTPIN (3100 2375) $PN 2
J 0
(3110 2355);
DISPLAY 0.489362 (3110 2355);
FORCEPROP 1 LAST MATERIAL X6S
J 0
(3150 2375);
DISPLAY 0.489362 (3150 2375);
PAINT SKYBLUE (3150 2375);
FORCEPROP 1 LAST TOLERANCE 20%
J 0
(3150 2425);
DISPLAY 0.489362 (3150 2425);
PAINT SKYBLUE (3150 2425);
FORCEPROP 1 LAST VALUE 22UF
J 0
(3150 2525);
DISPLAY 0.489362 (3150 2525);
PAINT SKYBLUE (3150 2525);
FORCEPROP 1 LAST VOLTAGE 4V
J 0
(3150 2475);
DISPLAY 0.489362 (3150 2475);
PAINT SKYBLUE (3150 2475);
FORCEPROP 1 LAST PACK_TYPE C0402
J 0
(3150 2275);
DISPLAY 0.489362 (3150 2275);
PAINT SKYBLUE (3150 2275);
FORCEPROP 2 LAST CDS_LIB pure_quanta
J 0
(3100 2475);
PAINT MONO (3100 2475);
DISPLAY INVISIBLE (3100 2475);
FORCEPROP 1 LAST PATH I42
J 0
(3150 2625);
DISPLAY 0.978723 (3150 2625);
PAINT WHITE (3150 2625);
DISPLAY INVISIBLE (3150 2625);
FORCEPROP 1 LAST PART_NUMBER CH622KMEB02
J 0
(3150 2325);
DISPLAY 0.489362 (3150 2325);
PAINT SKYBLUE (3150 2325);
DISPLAY INVISIBLE (3150 2325);
FORCEADD Q_CAP..1
(3550 2475);
FORCEPROP 1 LAST LOCATION C2461
J 0
(3600 2575);
DISPLAY 0.489362 (3600 2575);
PAINT SKYBLUE (3600 2575);
FORCEPROP 2 LAST $SEC 1
J 0
(3600 2675);
DISPLAY 0.680851 (3600 2675);
PAINT MONO (3600 2675);
DISPLAY INVISIBLE (3600 2675);
FORCEPROP 2 LAST CDS_SEC 1
J 0
(3600 2675);
DISPLAY 1.021277 (3600 2675);
DISPLAY INVISIBLE (3600 2675);
FORCEPROP 1 LASTPIN (3550 2575) $PN 1
J 0
(3560 2555);
DISPLAY 0.489362 (3560 2555);
FORCEPROP 1 LASTPIN (3550 2375) $PN 2
J 0
(3560 2355);
DISPLAY 0.489362 (3560 2355);
FORCEPROP 1 LAST MATERIAL X6S
J 0
(3600 2375);
DISPLAY 0.489362 (3600 2375);
PAINT SKYBLUE (3600 2375);
FORCEPROP 1 LAST TOLERANCE 20%
J 0
(3600 2425);
DISPLAY 0.489362 (3600 2425);
PAINT SKYBLUE (3600 2425);
FORCEPROP 1 LAST VALUE 22UF
J 0
(3600 2525);
DISPLAY 0.489362 (3600 2525);
PAINT SKYBLUE (3600 2525);
FORCEPROP 1 LAST VOLTAGE 4V
J 0
(3600 2475);
DISPLAY 0.489362 (3600 2475);
PAINT SKYBLUE (3600 2475);
FORCEPROP 1 LAST PACK_TYPE C0402
J 0
(3600 2275);
DISPLAY 0.489362 (3600 2275);
PAINT SKYBLUE (3600 2275);
FORCEPROP 2 LAST CDS_LIB pure_quanta
J 0
(3550 2475);
PAINT MONO (3550 2475);
DISPLAY INVISIBLE (3550 2475);
FORCEPROP 1 LAST PATH I43
J 0
(3600 2625);
DISPLAY 0.978723 (3600 2625);
PAINT WHITE (3600 2625);
DISPLAY INVISIBLE (3600 2625);
FORCEPROP 1 LAST PART_NUMBER CH622KMEB02
J 0
(3600 2325);
DISPLAY 0.489362 (3600 2325);
PAINT SKYBLUE (3600 2325);
DISPLAY INVISIBLE (3600 2325);
FORCEADD Q_CAP..1
(4000 2475);
FORCEPROP 1 LAST LOCATION C2468
J 0
(4050 2575);
DISPLAY 0.489362 (4050 2575);
PAINT SKYBLUE (4050 2575);
FORCEPROP 2 LAST $SEC 1
J 0
(4050 2675);
DISPLAY 0.680851 (4050 2675);
PAINT MONO (4050 2675);
DISPLAY INVISIBLE (4050 2675);
FORCEPROP 2 LAST CDS_SEC 1
J 0
(4050 2675);
DISPLAY 1.021277 (4050 2675);
DISPLAY INVISIBLE (4050 2675);
FORCEPROP 1 LASTPIN (4000 2575) $PN 1
J 0
(4010 2555);
DISPLAY 0.489362 (4010 2555);
FORCEPROP 1 LASTPIN (4000 2375) $PN 2
J 0
(4010 2355);
DISPLAY 0.489362 (4010 2355);
FORCEPROP 1 LAST MATERIAL X6S
J 0
(4050 2375);
DISPLAY 0.489362 (4050 2375);
PAINT SKYBLUE (4050 2375);
FORCEPROP 1 LAST TOLERANCE 20%
J 0
(4050 2425);
DISPLAY 0.489362 (4050 2425);
PAINT SKYBLUE (4050 2425);
FORCEPROP 1 LAST VALUE 22UF
J 0
(4050 2525);
DISPLAY 0.489362 (4050 2525);
PAINT SKYBLUE (4050 2525);
FORCEPROP 1 LAST VOLTAGE 4V
J 0
(4050 2475);
DISPLAY 0.489362 (4050 2475);
PAINT SKYBLUE (4050 2475);
FORCEPROP 1 LAST PACK_TYPE C0402
J 0
(4050 2275);
DISPLAY 0.489362 (4050 2275);
PAINT SKYBLUE (4050 2275);
FORCEPROP 2 LAST CDS_LIB pure_quanta
J 0
(4000 2475);
PAINT MONO (4000 2475);
DISPLAY INVISIBLE (4000 2475);
FORCEPROP 1 LAST PATH I44
J 0
(4050 2625);
DISPLAY 0.978723 (4050 2625);
PAINT WHITE (4050 2625);
DISPLAY INVISIBLE (4050 2625);
FORCEPROP 1 LAST PART_NUMBER CH622KMEB02
J 0
(4050 2325);
DISPLAY 0.489362 (4050 2325);
PAINT SKYBLUE (4050 2325);
DISPLAY INVISIBLE (4050 2325);
FORCEADD Q_CAP..1
(3550 3150);
FORCEPROP 1 LAST LOCATION C2460
J 0
(3600 3250);
DISPLAY 0.489362 (3600 3250);
PAINT SKYBLUE (3600 3250);
FORCEPROP 2 LAST $SEC 1
J 0
(3600 3350);
DISPLAY 0.680851 (3600 3350);
PAINT MONO (3600 3350);
DISPLAY INVISIBLE (3600 3350);
FORCEPROP 2 LAST CDS_SEC 1
J 0
(3600 3350);
DISPLAY 1.021277 (3600 3350);
DISPLAY INVISIBLE (3600 3350);
FORCEPROP 1 LASTPIN (3550 3250) $PN 1
J 0
(3560 3230);
DISPLAY 0.489362 (3560 3230);
FORCEPROP 1 LASTPIN (3550 3050) $PN 2
J 0
(3560 3030);
DISPLAY 0.489362 (3560 3030);
FORCEPROP 1 LAST MATERIAL X6S
J 0
(3600 3050);
DISPLAY 0.489362 (3600 3050);
PAINT SKYBLUE (3600 3050);
FORCEPROP 1 LAST TOLERANCE 20%
J 0
(3600 3100);
DISPLAY 0.489362 (3600 3100);
PAINT SKYBLUE (3600 3100);
FORCEPROP 1 LAST VALUE 22UF
J 0
(3600 3200);
DISPLAY 0.489362 (3600 3200);
PAINT SKYBLUE (3600 3200);
FORCEPROP 1 LAST VOLTAGE 4V
J 0
(3600 3150);
DISPLAY 0.489362 (3600 3150);
PAINT SKYBLUE (3600 3150);
FORCEPROP 1 LAST PACK_TYPE C0402
J 0
(3600 2950);
DISPLAY 0.489362 (3600 2950);
PAINT SKYBLUE (3600 2950);
FORCEPROP 2 LAST CDS_LIB pure_quanta
J 0
(3550 3150);
PAINT MONO (3550 3150);
DISPLAY INVISIBLE (3550 3150);
FORCEPROP 1 LAST PATH I45
J 0
(3600 3300);
DISPLAY 0.978723 (3600 3300);
PAINT WHITE (3600 3300);
DISPLAY INVISIBLE (3600 3300);
FORCEPROP 1 LAST PART_NUMBER CH622KMEB02
J 0
(3600 3000);
DISPLAY 0.489362 (3600 3000);
PAINT SKYBLUE (3600 3000);
DISPLAY INVISIBLE (3600 3000);
FORCEADD Q_CAP..1
(3550 3850);
FORCEPROP 1 LAST LOCATION C2459
J 0
(3600 3950);
DISPLAY 0.489362 (3600 3950);
PAINT SKYBLUE (3600 3950);
FORCEPROP 2 LAST $SEC 1
J 0
(3600 4050);
DISPLAY 0.680851 (3600 4050);
PAINT MONO (3600 4050);
DISPLAY INVISIBLE (3600 4050);
FORCEPROP 2 LAST CDS_SEC 1
J 0
(3600 4050);
DISPLAY 1.021277 (3600 4050);
DISPLAY INVISIBLE (3600 4050);
FORCEPROP 1 LASTPIN (3550 3950) $PN 1
J 0
(3560 3930);
DISPLAY 0.489362 (3560 3930);
FORCEPROP 1 LASTPIN (3550 3750) $PN 2
J 0
(3560 3730);
DISPLAY 0.489362 (3560 3730);
FORCEPROP 1 LAST MATERIAL X6S
J 0
(3600 3750);
DISPLAY 0.489362 (3600 3750);
PAINT SKYBLUE (3600 3750);
FORCEPROP 1 LAST TOLERANCE 20%
J 0
(3600 3800);
DISPLAY 0.489362 (3600 3800);
PAINT SKYBLUE (3600 3800);
FORCEPROP 1 LAST VALUE 22UF
J 0
(3600 3900);
DISPLAY 0.489362 (3600 3900);
PAINT SKYBLUE (3600 3900);
FORCEPROP 1 LAST VOLTAGE 4V
J 0
(3600 3850);
DISPLAY 0.489362 (3600 3850);
PAINT SKYBLUE (3600 3850);
FORCEPROP 1 LAST PACK_TYPE C0402
J 0
(3600 3650);
DISPLAY 0.489362 (3600 3650);
PAINT SKYBLUE (3600 3650);
FORCEPROP 2 LAST CDS_LIB pure_quanta
J 0
(3550 3850);
PAINT MONO (3550 3850);
DISPLAY INVISIBLE (3550 3850);
FORCEPROP 1 LAST PATH I46
J 0
(3600 4000);
DISPLAY 0.978723 (3600 4000);
PAINT WHITE (3600 4000);
DISPLAY INVISIBLE (3600 4000);
FORCEPROP 1 LAST PART_NUMBER CH622KMEB02
J 0
(3600 3700);
DISPLAY 0.489362 (3600 3700);
PAINT SKYBLUE (3600 3700);
DISPLAY INVISIBLE (3600 3700);
FORCEADD Q_CAP..1
(4000 3150);
FORCEPROP 1 LAST LOCATION C2467
J 0
(4050 3250);
DISPLAY 0.489362 (4050 3250);
PAINT SKYBLUE (4050 3250);
FORCEPROP 2 LAST $SEC 1
J 0
(4050 3350);
DISPLAY 0.680851 (4050 3350);
PAINT MONO (4050 3350);
DISPLAY INVISIBLE (4050 3350);
FORCEPROP 2 LAST CDS_SEC 1
J 0
(4050 3350);
DISPLAY 1.021277 (4050 3350);
DISPLAY INVISIBLE (4050 3350);
FORCEPROP 1 LASTPIN (4000 3250) $PN 1
J 0
(4010 3230);
DISPLAY 0.489362 (4010 3230);
FORCEPROP 1 LASTPIN (4000 3050) $PN 2
J 0
(4010 3030);
DISPLAY 0.489362 (4010 3030);
FORCEPROP 1 LAST MATERIAL X6S
J 0
(4050 3050);
DISPLAY 0.489362 (4050 3050);
PAINT SKYBLUE (4050 3050);
FORCEPROP 1 LAST TOLERANCE 20%
J 0
(4050 3100);
DISPLAY 0.489362 (4050 3100);
PAINT SKYBLUE (4050 3100);
FORCEPROP 1 LAST VALUE 22UF
J 0
(4050 3200);
DISPLAY 0.489362 (4050 3200);
PAINT SKYBLUE (4050 3200);
FORCEPROP 1 LAST VOLTAGE 4V
J 0
(4050 3150);
DISPLAY 0.489362 (4050 3150);
PAINT SKYBLUE (4050 3150);
FORCEPROP 1 LAST PACK_TYPE C0402
J 0
(4050 2950);
DISPLAY 0.489362 (4050 2950);
PAINT SKYBLUE (4050 2950);
FORCEPROP 2 LAST CDS_LIB pure_quanta
J 0
(4000 3150);
PAINT MONO (4000 3150);
DISPLAY INVISIBLE (4000 3150);
FORCEPROP 1 LAST PATH I47
J 0
(4050 3300);
DISPLAY 0.978723 (4050 3300);
PAINT WHITE (4050 3300);
DISPLAY INVISIBLE (4050 3300);
FORCEPROP 1 LAST PART_NUMBER CH622KMEB02
J 0
(4050 3000);
DISPLAY 0.489362 (4050 3000);
PAINT SKYBLUE (4050 3000);
DISPLAY INVISIBLE (4050 3000);
FORCEADD Q_CAP..1
(4000 3850);
FORCEPROP 1 LAST LOCATION C2466
J 0
(4050 3950);
DISPLAY 0.489362 (4050 3950);
PAINT SKYBLUE (4050 3950);
FORCEPROP 2 LAST $SEC 1
J 0
(4050 4050);
DISPLAY 0.680851 (4050 4050);
PAINT MONO (4050 4050);
DISPLAY INVISIBLE (4050 4050);
FORCEPROP 2 LAST CDS_SEC 1
J 0
(4050 4050);
DISPLAY 1.021277 (4050 4050);
DISPLAY INVISIBLE (4050 4050);
FORCEPROP 1 LASTPIN (4000 3950) $PN 1
J 0
(4010 3930);
DISPLAY 0.489362 (4010 3930);
FORCEPROP 1 LASTPIN (4000 3750) $PN 2
J 0
(4010 3730);
DISPLAY 0.489362 (4010 3730);
FORCEPROP 1 LAST MATERIAL X6S
J 0
(4050 3750);
DISPLAY 0.489362 (4050 3750);
PAINT SKYBLUE (4050 3750);
FORCEPROP 1 LAST TOLERANCE 20%
J 0
(4050 3800);
DISPLAY 0.489362 (4050 3800);
PAINT SKYBLUE (4050 3800);
FORCEPROP 1 LAST VALUE 22UF
J 0
(4050 3900);
DISPLAY 0.489362 (4050 3900);
PAINT SKYBLUE (4050 3900);
FORCEPROP 1 LAST VOLTAGE 4V
J 0
(4050 3850);
DISPLAY 0.489362 (4050 3850);
PAINT SKYBLUE (4050 3850);
FORCEPROP 1 LAST PACK_TYPE C0402
J 0
(4050 3650);
DISPLAY 0.489362 (4050 3650);
PAINT SKYBLUE (4050 3650);
FORCEPROP 2 LAST CDS_LIB pure_quanta
J 0
(4000 3850);
PAINT MONO (4000 3850);
DISPLAY INVISIBLE (4000 3850);
FORCEPROP 1 LAST PATH I48
J 0
(4050 4000);
DISPLAY 0.978723 (4050 4000);
PAINT WHITE (4050 4000);
DISPLAY INVISIBLE (4050 4000);
FORCEPROP 1 LAST PART_NUMBER CH622KMEB02
J 0
(4050 3700);
DISPLAY 0.489362 (4050 3700);
PAINT SKYBLUE (4050 3700);
DISPLAY INVISIBLE (4050 3700);
FORCEADD UNIVERSAL_POWER..1
(400 4125);
FORCEPROP 3 LASTPIN (400 4075) SIG_NAME PVDDCR_SOC_P1\g
J 0
(410 4085);
DISPLAY 0.659574 (410 4085);
PAINT MONO (410 4085);
DISPLAY INVISIBLE (410 4085);
FORCEPROP 1 LAST HDL_POWER PVDDCR_SOC_P1
J 1
(400 4175);
DISPLAY 0.489362 (400 4175);
PAINT GREEN (400 4175);
FORCEPROP 2 LAST CDS_LIB pure_quanta_power
J 0
(400 4125);
DISPLAY INVISIBLE (400 4125);
FORCEPROP 1 LAST PATH I49
J 0
(450 4150);
DISPLAY 0.872340 (450 4150);
PAINT AQUA (450 4150);
DISPLAY INVISIBLE (450 4150);
FORCEADD Q_CAP..1
(850 1800);
FORCEPROP 1 LAST LOCATION C2420
J 0
(900 1900);
DISPLAY 0.489362 (900 1900);
PAINT SKYBLUE (900 1900);
FORCEPROP 2 LAST $SEC 1
J 0
(900 2000);
DISPLAY 0.680851 (900 2000);
PAINT MONO (900 2000);
DISPLAY INVISIBLE (900 2000);
FORCEPROP 2 LAST CDS_SEC 1
J 0
(900 2000);
DISPLAY 1.021277 (900 2000);
DISPLAY INVISIBLE (900 2000);
FORCEPROP 1 LASTPIN (850 1900) $PN 1
J 0
(860 1880);
DISPLAY 0.489362 (860 1880);
FORCEPROP 1 LASTPIN (850 1700) $PN 2
J 0
(860 1680);
DISPLAY 0.489362 (860 1680);
FORCEPROP 1 LAST MATERIAL X6S
J 0
(900 1700);
DISPLAY 0.489362 (900 1700);
PAINT SKYBLUE (900 1700);
FORCEPROP 1 LAST TOLERANCE 20%
J 0
(900 1750);
DISPLAY 0.489362 (900 1750);
PAINT SKYBLUE (900 1750);
FORCEPROP 1 LAST VALUE 22UF
J 0
(900 1850);
DISPLAY 0.489362 (900 1850);
PAINT SKYBLUE (900 1850);
FORCEPROP 1 LAST VOLTAGE 4V
J 0
(900 1800);
DISPLAY 0.489362 (900 1800);
PAINT SKYBLUE (900 1800);
FORCEPROP 1 LAST PACK_TYPE C0402
J 0
(900 1600);
DISPLAY 0.489362 (900 1600);
PAINT SKYBLUE (900 1600);
FORCEPROP 2 LAST CDS_LIB pure_quanta
J 0
(850 1800);
PAINT MONO (850 1800);
DISPLAY INVISIBLE (850 1800);
FORCEPROP 1 LAST PATH I5
J 0
(900 1950);
DISPLAY 0.978723 (900 1950);
PAINT WHITE (900 1950);
DISPLAY INVISIBLE (900 1950);
FORCEPROP 1 LAST PART_NUMBER CH622KMEB02
J 0
(900 1650);
DISPLAY 0.489362 (900 1650);
PAINT SKYBLUE (900 1650);
DISPLAY INVISIBLE (900 1650);
FORCEADD Q_CAP..1
(400 4550);
FORCEPROP 1 LAST LOCATION C2409
J 0
(450 4650);
DISPLAY 0.489362 (450 4650);
PAINT SKYBLUE (450 4650);
FORCEPROP 2 LAST $SEC 1
J 0
(450 4750);
DISPLAY 0.680851 (450 4750);
PAINT MONO (450 4750);
DISPLAY INVISIBLE (450 4750);
FORCEPROP 2 LAST CDS_SEC 1
J 0
(450 4750);
DISPLAY 1.021277 (450 4750);
DISPLAY INVISIBLE (450 4750);
FORCEPROP 1 LASTPIN (400 4650) $PN 1
J 0
(410 4630);
DISPLAY 0.489362 (410 4630);
FORCEPROP 1 LASTPIN (400 4450) $PN 2
J 0
(410 4430);
DISPLAY 0.489362 (410 4430);
FORCEPROP 1 LAST MATERIAL X6S
J 0
(450 4450);
DISPLAY 0.489362 (450 4450);
PAINT SKYBLUE (450 4450);
FORCEPROP 1 LAST TOLERANCE 20%
J 0
(450 4500);
DISPLAY 0.489362 (450 4500);
PAINT SKYBLUE (450 4500);
FORCEPROP 1 LAST VALUE 22UF
J 0
(450 4600);
DISPLAY 0.489362 (450 4600);
PAINT SKYBLUE (450 4600);
FORCEPROP 1 LAST VOLTAGE 4V
J 0
(450 4550);
DISPLAY 0.489362 (450 4550);
PAINT SKYBLUE (450 4550);
FORCEPROP 1 LAST PACK_TYPE C0402
J 0
(450 4350);
DISPLAY 0.489362 (450 4350);
PAINT SKYBLUE (450 4350);
FORCEPROP 2 LAST CDS_LIB pure_quanta
J 0
(400 4550);
PAINT MONO (400 4550);
DISPLAY INVISIBLE (400 4550);
FORCEPROP 1 LAST PATH I50
J 0
(450 4700);
DISPLAY 0.978723 (450 4700);
PAINT WHITE (450 4700);
DISPLAY INVISIBLE (450 4700);
FORCEPROP 1 LAST PART_NUMBER CH622KMEB02
J 0
(450 4400);
DISPLAY 0.489362 (450 4400);
PAINT SKYBLUE (450 4400);
DISPLAY INVISIBLE (450 4400);
FORCEADD UNIVERSAL_POWER..1
(400 4825);
FORCEPROP 3 LASTPIN (400 4775) SIG_NAME PVDDCR_SOC_P1\g
J 0
(410 4785);
DISPLAY 0.659574 (410 4785);
PAINT MONO (410 4785);
DISPLAY INVISIBLE (410 4785);
FORCEPROP 1 LAST HDL_POWER PVDDCR_SOC_P1
J 1
(400 4900);
DISPLAY 0.489362 (400 4900);
PAINT GREEN (400 4900);
FORCEPROP 2 LAST CDS_LIB pure_quanta_power
J 0
(400 4825);
DISPLAY INVISIBLE (400 4825);
FORCEPROP 1 LAST PATH I51
J 0
(450 4850);
DISPLAY 0.872340 (450 4850);
PAINT AQUA (450 4850);
DISPLAY INVISIBLE (450 4850);
FORCEADD Q_CAP..1
(850 4550);
FORCEPROP 1 LAST LOCATION C2416
J 0
(900 4650);
DISPLAY 0.489362 (900 4650);
PAINT SKYBLUE (900 4650);
FORCEPROP 2 LAST $SEC 1
J 0
(900 4750);
DISPLAY 0.680851 (900 4750);
PAINT MONO (900 4750);
DISPLAY INVISIBLE (900 4750);
FORCEPROP 2 LAST CDS_SEC 1
J 0
(900 4750);
DISPLAY 1.021277 (900 4750);
DISPLAY INVISIBLE (900 4750);
FORCEPROP 1 LASTPIN (850 4650) $PN 1
J 0
(860 4630);
DISPLAY 0.489362 (860 4630);
FORCEPROP 1 LASTPIN (850 4450) $PN 2
J 0
(860 4430);
DISPLAY 0.489362 (860 4430);
FORCEPROP 1 LAST MATERIAL X6S
J 0
(900 4450);
DISPLAY 0.489362 (900 4450);
PAINT SKYBLUE (900 4450);
FORCEPROP 1 LAST TOLERANCE 20%
J 0
(900 4500);
DISPLAY 0.489362 (900 4500);
PAINT SKYBLUE (900 4500);
FORCEPROP 1 LAST VALUE 22UF
J 0
(900 4600);
DISPLAY 0.489362 (900 4600);
PAINT SKYBLUE (900 4600);
FORCEPROP 1 LAST VOLTAGE 4V
J 0
(900 4550);
DISPLAY 0.489362 (900 4550);
PAINT SKYBLUE (900 4550);
FORCEPROP 1 LAST PACK_TYPE C0402
J 0
(900 4350);
DISPLAY 0.489362 (900 4350);
PAINT SKYBLUE (900 4350);
FORCEPROP 2 LAST CDS_LIB pure_quanta
J 0
(850 4550);
PAINT MONO (850 4550);
DISPLAY INVISIBLE (850 4550);
FORCEPROP 1 LAST PATH I52
J 0
(900 4700);
DISPLAY 0.978723 (900 4700);
PAINT WHITE (900 4700);
DISPLAY INVISIBLE (900 4700);
FORCEPROP 1 LAST PART_NUMBER CH622KMEB02
J 0
(900 4400);
DISPLAY 0.489362 (900 4400);
PAINT SKYBLUE (900 4400);
DISPLAY INVISIBLE (900 4400);
FORCEADD Q_CAP..1
(400 5225);
FORCEPROP 1 LAST LOCATION C2408
J 0
(450 5325);
DISPLAY 0.489362 (450 5325);
PAINT SKYBLUE (450 5325);
FORCEPROP 2 LAST $SEC 1
J 0
(450 5425);
DISPLAY 0.680851 (450 5425);
PAINT MONO (450 5425);
DISPLAY INVISIBLE (450 5425);
FORCEPROP 2 LAST CDS_SEC 1
J 0
(450 5425);
DISPLAY 1.021277 (450 5425);
DISPLAY INVISIBLE (450 5425);
FORCEPROP 1 LASTPIN (400 5325) $PN 1
J 0
(410 5305);
DISPLAY 0.489362 (410 5305);
FORCEPROP 1 LASTPIN (400 5125) $PN 2
J 0
(410 5105);
DISPLAY 0.489362 (410 5105);
FORCEPROP 1 LAST MATERIAL X6S
J 0
(450 5125);
DISPLAY 0.489362 (450 5125);
PAINT SKYBLUE (450 5125);
FORCEPROP 1 LAST TOLERANCE 20%
J 0
(450 5175);
DISPLAY 0.489362 (450 5175);
PAINT SKYBLUE (450 5175);
FORCEPROP 1 LAST VALUE 22UF
J 0
(450 5275);
DISPLAY 0.489362 (450 5275);
PAINT SKYBLUE (450 5275);
FORCEPROP 1 LAST VOLTAGE 4V
J 0
(450 5225);
DISPLAY 0.489362 (450 5225);
PAINT SKYBLUE (450 5225);
FORCEPROP 1 LAST PACK_TYPE C0402
J 0
(450 5025);
DISPLAY 0.489362 (450 5025);
PAINT SKYBLUE (450 5025);
FORCEPROP 2 LAST CDS_LIB pure_quanta
J 0
(400 5225);
PAINT MONO (400 5225);
DISPLAY INVISIBLE (400 5225);
FORCEPROP 1 LAST PATH I53
J 0
(450 5375);
DISPLAY 0.978723 (450 5375);
PAINT WHITE (450 5375);
DISPLAY INVISIBLE (450 5375);
FORCEPROP 1 LAST PART_NUMBER CH622KMEB02
J 0
(450 5075);
DISPLAY 0.489362 (450 5075);
PAINT SKYBLUE (450 5075);
DISPLAY INVISIBLE (450 5075);
FORCEADD UNIVERSAL_POWER..1
(400 5500);
FORCEPROP 3 LASTPIN (400 5450) SIG_NAME PVDDCR_SOC_P1\g
J 0
(410 5460);
DISPLAY 0.659574 (410 5460);
PAINT MONO (410 5460);
DISPLAY INVISIBLE (410 5460);
FORCEPROP 1 LAST HDL_POWER PVDDCR_SOC_P1
J 1
(400 5550);
DISPLAY 0.489362 (400 5550);
PAINT GREEN (400 5550);
FORCEPROP 2 LAST CDS_LIB pure_quanta_power
J 0
(400 5500);
DISPLAY INVISIBLE (400 5500);
FORCEPROP 1 LAST PATH I54
J 0
(450 5525);
DISPLAY 0.872340 (450 5525);
PAINT AQUA (450 5525);
DISPLAY INVISIBLE (450 5525);
FORCEADD Q_CAP..1
(400 5875);
FORCEPROP 1 LAST LOCATION C2407
J 0
(450 5975);
DISPLAY 0.489362 (450 5975);
PAINT SKYBLUE (450 5975);
FORCEPROP 2 LAST $SEC 1
J 0
(450 6075);
DISPLAY 0.680851 (450 6075);
PAINT MONO (450 6075);
DISPLAY INVISIBLE (450 6075);
FORCEPROP 2 LAST CDS_SEC 1
J 0
(450 6075);
DISPLAY 1.021277 (450 6075);
DISPLAY INVISIBLE (450 6075);
FORCEPROP 1 LASTPIN (400 5975) $PN 1
J 0
(410 5955);
DISPLAY 0.489362 (410 5955);
FORCEPROP 1 LASTPIN (400 5775) $PN 2
J 0
(410 5755);
DISPLAY 0.489362 (410 5755);
FORCEPROP 1 LAST MATERIAL X6S
J 0
(450 5775);
DISPLAY 0.489362 (450 5775);
PAINT SKYBLUE (450 5775);
FORCEPROP 1 LAST TOLERANCE 20%
J 0
(450 5825);
DISPLAY 0.489362 (450 5825);
PAINT SKYBLUE (450 5825);
FORCEPROP 1 LAST VALUE 22UF
J 0
(450 5925);
DISPLAY 0.489362 (450 5925);
PAINT SKYBLUE (450 5925);
FORCEPROP 1 LAST VOLTAGE 4V
J 0
(450 5875);
DISPLAY 0.489362 (450 5875);
PAINT SKYBLUE (450 5875);
FORCEPROP 1 LAST PACK_TYPE C0402
J 0
(450 5675);
DISPLAY 0.489362 (450 5675);
PAINT SKYBLUE (450 5675);
FORCEPROP 2 LAST CDS_LIB pure_quanta
J 0
(400 5875);
PAINT MONO (400 5875);
DISPLAY INVISIBLE (400 5875);
FORCEPROP 1 LAST PATH I55
J 0
(450 6025);
DISPLAY 0.978723 (450 6025);
PAINT WHITE (450 6025);
DISPLAY INVISIBLE (450 6025);
FORCEPROP 1 LAST PART_NUMBER CH622KMEB02
J 0
(450 5725);
DISPLAY 0.489362 (450 5725);
PAINT SKYBLUE (450 5725);
DISPLAY INVISIBLE (450 5725);
FORCEADD Q_CAP..1
(850 5225);
FORCEPROP 1 LAST LOCATION C2415
J 0
(900 5325);
DISPLAY 0.489362 (900 5325);
PAINT SKYBLUE (900 5325);
FORCEPROP 2 LAST $SEC 1
J 0
(900 5425);
DISPLAY 0.680851 (900 5425);
PAINT MONO (900 5425);
DISPLAY INVISIBLE (900 5425);
FORCEPROP 2 LAST CDS_SEC 1
J 0
(900 5425);
DISPLAY 1.021277 (900 5425);
DISPLAY INVISIBLE (900 5425);
FORCEPROP 1 LASTPIN (850 5325) $PN 1
J 0
(860 5305);
DISPLAY 0.489362 (860 5305);
FORCEPROP 1 LASTPIN (850 5125) $PN 2
J 0
(860 5105);
DISPLAY 0.489362 (860 5105);
FORCEPROP 1 LAST MATERIAL X6S
J 0
(900 5125);
DISPLAY 0.489362 (900 5125);
PAINT SKYBLUE (900 5125);
FORCEPROP 1 LAST TOLERANCE 20%
J 0
(900 5175);
DISPLAY 0.489362 (900 5175);
PAINT SKYBLUE (900 5175);
FORCEPROP 1 LAST VALUE 22UF
J 0
(900 5275);
DISPLAY 0.489362 (900 5275);
PAINT SKYBLUE (900 5275);
FORCEPROP 1 LAST VOLTAGE 4V
J 0
(900 5225);
DISPLAY 0.489362 (900 5225);
PAINT SKYBLUE (900 5225);
FORCEPROP 1 LAST PACK_TYPE C0402
J 0
(900 5025);
DISPLAY 0.489362 (900 5025);
PAINT SKYBLUE (900 5025);
FORCEPROP 2 LAST CDS_LIB pure_quanta
J 0
(850 5225);
PAINT MONO (850 5225);
DISPLAY INVISIBLE (850 5225);
FORCEPROP 1 LAST PATH I56
J 0
(900 5375);
DISPLAY 0.978723 (900 5375);
PAINT WHITE (900 5375);
DISPLAY INVISIBLE (900 5375);
FORCEPROP 1 LAST PART_NUMBER CH622KMEB02
J 0
(900 5075);
DISPLAY 0.489362 (900 5075);
PAINT SKYBLUE (900 5075);
DISPLAY INVISIBLE (900 5075);
FORCEADD Q_CAP..1
(850 5875);
FORCEPROP 1 LAST LOCATION C2414
J 0
(900 5975);
DISPLAY 0.489362 (900 5975);
PAINT SKYBLUE (900 5975);
FORCEPROP 2 LAST $SEC 1
J 0
(900 6075);
DISPLAY 0.680851 (900 6075);
PAINT MONO (900 6075);
DISPLAY INVISIBLE (900 6075);
FORCEPROP 2 LAST CDS_SEC 1
J 0
(900 6075);
DISPLAY 1.021277 (900 6075);
DISPLAY INVISIBLE (900 6075);
FORCEPROP 1 LASTPIN (850 5975) $PN 1
J 0
(860 5955);
DISPLAY 0.489362 (860 5955);
FORCEPROP 1 LASTPIN (850 5775) $PN 2
J 0
(860 5755);
DISPLAY 0.489362 (860 5755);
FORCEPROP 1 LAST MATERIAL X6S
J 0
(900 5775);
DISPLAY 0.489362 (900 5775);
PAINT SKYBLUE (900 5775);
FORCEPROP 1 LAST TOLERANCE 20%
J 0
(900 5825);
DISPLAY 0.489362 (900 5825);
PAINT SKYBLUE (900 5825);
FORCEPROP 1 LAST VALUE 22UF
J 0
(900 5925);
DISPLAY 0.489362 (900 5925);
PAINT SKYBLUE (900 5925);
FORCEPROP 1 LAST VOLTAGE 4V
J 0
(900 5875);
DISPLAY 0.489362 (900 5875);
PAINT SKYBLUE (900 5875);
FORCEPROP 1 LAST PACK_TYPE C0402
J 0
(900 5675);
DISPLAY 0.489362 (900 5675);
PAINT SKYBLUE (900 5675);
FORCEPROP 2 LAST CDS_LIB pure_quanta
J 0
(850 5875);
PAINT MONO (850 5875);
DISPLAY INVISIBLE (850 5875);
FORCEPROP 1 LAST PATH I57
J 0
(900 6025);
DISPLAY 0.978723 (900 6025);
PAINT WHITE (900 6025);
DISPLAY INVISIBLE (900 6025);
FORCEPROP 1 LAST PART_NUMBER CH622KMEB02
J 0
(900 5725);
DISPLAY 0.489362 (900 5725);
PAINT SKYBLUE (900 5725);
DISPLAY INVISIBLE (900 5725);
FORCEADD Q_CAP..1
(1300 4550);
FORCEPROP 1 LAST LOCATION C2423
J 0
(1350 4650);
DISPLAY 0.489362 (1350 4650);
PAINT SKYBLUE (1350 4650);
FORCEPROP 2 LAST $SEC 1
J 0
(1350 4750);
DISPLAY 0.680851 (1350 4750);
PAINT MONO (1350 4750);
DISPLAY INVISIBLE (1350 4750);
FORCEPROP 2 LAST CDS_SEC 1
J 0
(1350 4750);
DISPLAY 1.021277 (1350 4750);
DISPLAY INVISIBLE (1350 4750);
FORCEPROP 1 LASTPIN (1300 4650) $PN 1
J 0
(1310 4630);
DISPLAY 0.489362 (1310 4630);
FORCEPROP 1 LASTPIN (1300 4450) $PN 2
J 0
(1310 4430);
DISPLAY 0.489362 (1310 4430);
FORCEPROP 1 LAST MATERIAL X6S
J 0
(1350 4450);
DISPLAY 0.489362 (1350 4450);
PAINT SKYBLUE (1350 4450);
FORCEPROP 1 LAST TOLERANCE 20%
J 0
(1350 4500);
DISPLAY 0.489362 (1350 4500);
PAINT SKYBLUE (1350 4500);
FORCEPROP 1 LAST VALUE 22UF
J 0
(1350 4600);
DISPLAY 0.489362 (1350 4600);
PAINT SKYBLUE (1350 4600);
FORCEPROP 1 LAST VOLTAGE 4V
J 0
(1350 4550);
DISPLAY 0.489362 (1350 4550);
PAINT SKYBLUE (1350 4550);
FORCEPROP 1 LAST PACK_TYPE C0402
J 0
(1350 4350);
DISPLAY 0.489362 (1350 4350);
PAINT SKYBLUE (1350 4350);
FORCEPROP 2 LAST CDS_LIB pure_quanta
J 0
(1300 4550);
PAINT MONO (1300 4550);
DISPLAY INVISIBLE (1300 4550);
FORCEPROP 1 LAST PATH I58
J 0
(1350 4700);
DISPLAY 0.978723 (1350 4700);
PAINT WHITE (1350 4700);
DISPLAY INVISIBLE (1350 4700);
FORCEPROP 1 LAST PART_NUMBER CH622KMEB02
J 0
(1350 4400);
DISPLAY 0.489362 (1350 4400);
PAINT SKYBLUE (1350 4400);
DISPLAY INVISIBLE (1350 4400);
FORCEADD Q_CAP..1
(1750 4550);
FORCEPROP 1 LAST LOCATION C2430
J 0
(1800 4650);
DISPLAY 0.489362 (1800 4650);
PAINT SKYBLUE (1800 4650);
FORCEPROP 2 LAST $SEC 1
J 0
(1800 4750);
DISPLAY 0.680851 (1800 4750);
PAINT MONO (1800 4750);
DISPLAY INVISIBLE (1800 4750);
FORCEPROP 2 LAST CDS_SEC 1
J 0
(1800 4750);
DISPLAY 1.021277 (1800 4750);
DISPLAY INVISIBLE (1800 4750);
FORCEPROP 1 LASTPIN (1750 4650) $PN 1
J 0
(1760 4630);
DISPLAY 0.489362 (1760 4630);
FORCEPROP 1 LASTPIN (1750 4450) $PN 2
J 0
(1760 4430);
DISPLAY 0.489362 (1760 4430);
FORCEPROP 1 LAST MATERIAL X6S
J 0
(1800 4450);
DISPLAY 0.489362 (1800 4450);
PAINT SKYBLUE (1800 4450);
FORCEPROP 1 LAST TOLERANCE 20%
J 0
(1800 4500);
DISPLAY 0.489362 (1800 4500);
PAINT SKYBLUE (1800 4500);
FORCEPROP 1 LAST VALUE 22UF
J 0
(1800 4600);
DISPLAY 0.489362 (1800 4600);
PAINT SKYBLUE (1800 4600);
FORCEPROP 1 LAST VOLTAGE 4V
J 0
(1800 4550);
DISPLAY 0.489362 (1800 4550);
PAINT SKYBLUE (1800 4550);
FORCEPROP 1 LAST PACK_TYPE C0402
J 0
(1800 4350);
DISPLAY 0.489362 (1800 4350);
PAINT SKYBLUE (1800 4350);
FORCEPROP 2 LAST CDS_LIB pure_quanta
J 0
(1750 4550);
PAINT MONO (1750 4550);
DISPLAY INVISIBLE (1750 4550);
FORCEPROP 1 LAST PATH I59
J 0
(1800 4700);
DISPLAY 0.978723 (1800 4700);
PAINT WHITE (1800 4700);
DISPLAY INVISIBLE (1800 4700);
FORCEPROP 1 LAST PART_NUMBER CH622KMEB02
J 0
(1800 4400);
DISPLAY 0.489362 (1800 4400);
PAINT SKYBLUE (1800 4400);
DISPLAY INVISIBLE (1800 4400);
FORCEADD Q_CAP..1
(1300 1075);
FORCEPROP 1 LAST LOCATION C3914
J 0
(1350 1175);
DISPLAY 0.489362 (1350 1175);
PAINT SKYBLUE (1350 1175);
FORCEPROP 2 LAST $SEC 1
J 0
(1350 1275);
DISPLAY 0.680851 (1350 1275);
PAINT MONO (1350 1275);
DISPLAY INVISIBLE (1350 1275);
FORCEPROP 2 LAST CDS_SEC 1
J 0
(1350 1275);
DISPLAY 1.021277 (1350 1275);
DISPLAY INVISIBLE (1350 1275);
FORCEPROP 1 LASTPIN (1300 1175) $PN 1
J 0
(1310 1155);
DISPLAY 0.489362 (1310 1155);
FORCEPROP 1 LASTPIN (1300 975) $PN 2
J 0
(1310 955);
DISPLAY 0.489362 (1310 955);
FORCEPROP 1 LAST MATERIAL X6S
J 0
(1350 975);
DISPLAY 0.489362 (1350 975);
PAINT SKYBLUE (1350 975);
FORCEPROP 1 LAST TOLERANCE 20%
J 0
(1350 1025);
DISPLAY 0.489362 (1350 1025);
PAINT SKYBLUE (1350 1025);
FORCEPROP 1 LAST VALUE 22UF
J 0
(1350 1125);
DISPLAY 0.489362 (1350 1125);
PAINT SKYBLUE (1350 1125);
FORCEPROP 1 LAST VOLTAGE 4V
J 0
(1350 1075);
DISPLAY 0.489362 (1350 1075);
PAINT SKYBLUE (1350 1075);
FORCEPROP 1 LAST PACK_TYPE C0402
J 0
(1350 875);
DISPLAY 0.489362 (1350 875);
PAINT SKYBLUE (1350 875);
FORCEPROP 2 LAST CDS_LIB pure_quanta
J 0
(1300 1075);
PAINT MONO (1300 1075);
DISPLAY INVISIBLE (1300 1075);
FORCEPROP 1 LAST PATH I6
J 0
(1350 1225);
DISPLAY 0.978723 (1350 1225);
PAINT WHITE (1350 1225);
DISPLAY INVISIBLE (1350 1225);
FORCEPROP 1 LAST PART_NUMBER CH622KMEB02
J 0
(1350 925);
DISPLAY 0.489362 (1350 925);
PAINT SKYBLUE (1350 925);
DISPLAY INVISIBLE (1350 925);
FORCEADD Q_CAP..1
(1300 5225);
FORCEPROP 1 LAST LOCATION C2422
J 0
(1350 5325);
DISPLAY 0.489362 (1350 5325);
PAINT SKYBLUE (1350 5325);
FORCEPROP 2 LAST $SEC 1
J 0
(1350 5425);
DISPLAY 0.680851 (1350 5425);
PAINT MONO (1350 5425);
DISPLAY INVISIBLE (1350 5425);
FORCEPROP 2 LAST CDS_SEC 1
J 0
(1350 5425);
DISPLAY 1.021277 (1350 5425);
DISPLAY INVISIBLE (1350 5425);
FORCEPROP 1 LASTPIN (1300 5325) $PN 1
J 0
(1310 5305);
DISPLAY 0.489362 (1310 5305);
FORCEPROP 1 LASTPIN (1300 5125) $PN 2
J 0
(1310 5105);
DISPLAY 0.489362 (1310 5105);
FORCEPROP 1 LAST MATERIAL X6S
J 0
(1350 5125);
DISPLAY 0.489362 (1350 5125);
PAINT SKYBLUE (1350 5125);
FORCEPROP 1 LAST TOLERANCE 20%
J 0
(1350 5175);
DISPLAY 0.489362 (1350 5175);
PAINT SKYBLUE (1350 5175);
FORCEPROP 1 LAST VALUE 22UF
J 0
(1350 5275);
DISPLAY 0.489362 (1350 5275);
PAINT SKYBLUE (1350 5275);
FORCEPROP 1 LAST VOLTAGE 4V
J 0
(1350 5225);
DISPLAY 0.489362 (1350 5225);
PAINT SKYBLUE (1350 5225);
FORCEPROP 1 LAST PACK_TYPE C0402
J 0
(1350 5025);
DISPLAY 0.489362 (1350 5025);
PAINT SKYBLUE (1350 5025);
FORCEPROP 2 LAST CDS_LIB pure_quanta
J 0
(1300 5225);
PAINT MONO (1300 5225);
DISPLAY INVISIBLE (1300 5225);
FORCEPROP 1 LAST PATH I60
J 0
(1350 5375);
DISPLAY 0.978723 (1350 5375);
PAINT WHITE (1350 5375);
DISPLAY INVISIBLE (1350 5375);
FORCEPROP 1 LAST PART_NUMBER CH622KMEB02
J 0
(1350 5075);
DISPLAY 0.489362 (1350 5075);
PAINT SKYBLUE (1350 5075);
DISPLAY INVISIBLE (1350 5075);
FORCEADD Q_CAP..1
(1300 5875);
FORCEPROP 1 LAST LOCATION C2421
J 0
(1350 5975);
DISPLAY 0.489362 (1350 5975);
PAINT SKYBLUE (1350 5975);
FORCEPROP 2 LAST $SEC 1
J 0
(1350 6075);
DISPLAY 0.680851 (1350 6075);
PAINT MONO (1350 6075);
DISPLAY INVISIBLE (1350 6075);
FORCEPROP 2 LAST CDS_SEC 1
J 0
(1350 6075);
DISPLAY 1.021277 (1350 6075);
DISPLAY INVISIBLE (1350 6075);
FORCEPROP 1 LASTPIN (1300 5975) $PN 1
J 0
(1310 5955);
DISPLAY 0.489362 (1310 5955);
FORCEPROP 1 LASTPIN (1300 5775) $PN 2
J 0
(1310 5755);
DISPLAY 0.489362 (1310 5755);
FORCEPROP 1 LAST MATERIAL X6S
J 0
(1350 5775);
DISPLAY 0.489362 (1350 5775);
PAINT SKYBLUE (1350 5775);
FORCEPROP 1 LAST TOLERANCE 20%
J 0
(1350 5825);
DISPLAY 0.489362 (1350 5825);
PAINT SKYBLUE (1350 5825);
FORCEPROP 1 LAST VALUE 22UF
J 0
(1350 5925);
DISPLAY 0.489362 (1350 5925);
PAINT SKYBLUE (1350 5925);
FORCEPROP 1 LAST VOLTAGE 4V
J 0
(1350 5875);
DISPLAY 0.489362 (1350 5875);
PAINT SKYBLUE (1350 5875);
FORCEPROP 1 LAST PACK_TYPE C0402
J 0
(1350 5675);
DISPLAY 0.489362 (1350 5675);
PAINT SKYBLUE (1350 5675);
FORCEPROP 2 LAST CDS_LIB pure_quanta
J 0
(1300 5875);
PAINT MONO (1300 5875);
DISPLAY INVISIBLE (1300 5875);
FORCEPROP 1 LAST PATH I61
J 0
(1350 6025);
DISPLAY 0.978723 (1350 6025);
PAINT WHITE (1350 6025);
DISPLAY INVISIBLE (1350 6025);
FORCEPROP 1 LAST PART_NUMBER CH622KMEB02
J 0
(1350 5725);
DISPLAY 0.489362 (1350 5725);
PAINT SKYBLUE (1350 5725);
DISPLAY INVISIBLE (1350 5725);
FORCEADD Q_CAP..1
(1750 5225);
FORCEPROP 1 LAST LOCATION C2429
J 0
(1800 5325);
DISPLAY 0.489362 (1800 5325);
PAINT SKYBLUE (1800 5325);
FORCEPROP 2 LAST $SEC 1
J 0
(1800 5425);
DISPLAY 0.680851 (1800 5425);
PAINT MONO (1800 5425);
DISPLAY INVISIBLE (1800 5425);
FORCEPROP 2 LAST CDS_SEC 1
J 0
(1800 5425);
DISPLAY 1.021277 (1800 5425);
DISPLAY INVISIBLE (1800 5425);
FORCEPROP 1 LASTPIN (1750 5325) $PN 1
J 0
(1760 5305);
DISPLAY 0.489362 (1760 5305);
FORCEPROP 1 LASTPIN (1750 5125) $PN 2
J 0
(1760 5105);
DISPLAY 0.489362 (1760 5105);
FORCEPROP 1 LAST MATERIAL X6S
J 0
(1800 5125);
DISPLAY 0.489362 (1800 5125);
PAINT SKYBLUE (1800 5125);
FORCEPROP 1 LAST TOLERANCE 20%
J 0
(1800 5175);
DISPLAY 0.489362 (1800 5175);
PAINT SKYBLUE (1800 5175);
FORCEPROP 1 LAST VALUE 22UF
J 0
(1800 5275);
DISPLAY 0.489362 (1800 5275);
PAINT SKYBLUE (1800 5275);
FORCEPROP 1 LAST VOLTAGE 4V
J 0
(1800 5225);
DISPLAY 0.489362 (1800 5225);
PAINT SKYBLUE (1800 5225);
FORCEPROP 1 LAST PACK_TYPE C0402
J 0
(1800 5025);
DISPLAY 0.489362 (1800 5025);
PAINT SKYBLUE (1800 5025);
FORCEPROP 2 LAST CDS_LIB pure_quanta
J 0
(1750 5225);
PAINT MONO (1750 5225);
DISPLAY INVISIBLE (1750 5225);
FORCEPROP 1 LAST PATH I62
J 0
(1800 5375);
DISPLAY 0.978723 (1800 5375);
PAINT WHITE (1800 5375);
DISPLAY INVISIBLE (1800 5375);
FORCEPROP 1 LAST PART_NUMBER CH622KMEB02
J 0
(1800 5075);
DISPLAY 0.489362 (1800 5075);
PAINT SKYBLUE (1800 5075);
DISPLAY INVISIBLE (1800 5075);
FORCEADD UNIVERSAL_POWER..1
(400 6150);
FORCEPROP 3 LASTPIN (400 6100) SIG_NAME PVDDCR_SOC_P1\g
J 0
(410 6110);
DISPLAY 0.659574 (410 6110);
PAINT MONO (410 6110);
DISPLAY INVISIBLE (410 6110);
FORCEPROP 1 LAST HDL_POWER PVDDCR_SOC_P1
J 1
(400 6200);
DISPLAY 0.489362 (400 6200);
PAINT GREEN (400 6200);
FORCEPROP 2 LAST CDS_LIB pure_quanta_power
J 0
(400 6150);
DISPLAY INVISIBLE (400 6150);
FORCEPROP 1 LAST PATH I63
J 0
(450 6175);
DISPLAY 0.872340 (450 6175);
PAINT AQUA (450 6175);
DISPLAY INVISIBLE (450 6175);
FORCEADD Q_CAP..1
(2200 4550);
FORCEPROP 1 LAST LOCATION C2437
J 0
(2250 4650);
DISPLAY 0.489362 (2250 4650);
PAINT SKYBLUE (2250 4650);
FORCEPROP 2 LAST $SEC 1
J 0
(2250 4750);
DISPLAY 0.680851 (2250 4750);
PAINT MONO (2250 4750);
DISPLAY INVISIBLE (2250 4750);
FORCEPROP 2 LAST CDS_SEC 1
J 0
(2250 4750);
DISPLAY 1.021277 (2250 4750);
DISPLAY INVISIBLE (2250 4750);
FORCEPROP 1 LASTPIN (2200 4650) $PN 1
J 0
(2210 4630);
DISPLAY 0.489362 (2210 4630);
FORCEPROP 1 LASTPIN (2200 4450) $PN 2
J 0
(2210 4430);
DISPLAY 0.489362 (2210 4430);
FORCEPROP 1 LAST MATERIAL X6S
J 0
(2250 4450);
DISPLAY 0.489362 (2250 4450);
PAINT SKYBLUE (2250 4450);
FORCEPROP 1 LAST TOLERANCE 20%
J 0
(2250 4500);
DISPLAY 0.489362 (2250 4500);
PAINT SKYBLUE (2250 4500);
FORCEPROP 1 LAST VALUE 22UF
J 0
(2250 4600);
DISPLAY 0.489362 (2250 4600);
PAINT SKYBLUE (2250 4600);
FORCEPROP 1 LAST VOLTAGE 4V
J 0
(2250 4550);
DISPLAY 0.489362 (2250 4550);
PAINT SKYBLUE (2250 4550);
FORCEPROP 1 LAST PACK_TYPE C0402
J 0
(2250 4350);
DISPLAY 0.489362 (2250 4350);
PAINT SKYBLUE (2250 4350);
FORCEPROP 2 LAST CDS_LIB pure_quanta
J 0
(2200 4550);
PAINT MONO (2200 4550);
DISPLAY INVISIBLE (2200 4550);
FORCEPROP 1 LAST PATH I64
J 0
(2250 4700);
DISPLAY 0.978723 (2250 4700);
PAINT WHITE (2250 4700);
DISPLAY INVISIBLE (2250 4700);
FORCEPROP 1 LAST PART_NUMBER CH622KMEB02
J 0
(2250 4400);
DISPLAY 0.489362 (2250 4400);
PAINT SKYBLUE (2250 4400);
DISPLAY INVISIBLE (2250 4400);
FORCEADD Q_CAP..1
(2650 4550);
FORCEPROP 1 LAST LOCATION C2444
J 0
(2700 4650);
DISPLAY 0.489362 (2700 4650);
PAINT SKYBLUE (2700 4650);
FORCEPROP 2 LAST $SEC 1
J 0
(2700 4750);
DISPLAY 0.680851 (2700 4750);
PAINT MONO (2700 4750);
DISPLAY INVISIBLE (2700 4750);
FORCEPROP 2 LAST CDS_SEC 1
J 0
(2700 4750);
DISPLAY 1.021277 (2700 4750);
DISPLAY INVISIBLE (2700 4750);
FORCEPROP 1 LASTPIN (2650 4650) $PN 1
J 0
(2660 4630);
DISPLAY 0.489362 (2660 4630);
FORCEPROP 1 LASTPIN (2650 4450) $PN 2
J 0
(2660 4430);
DISPLAY 0.489362 (2660 4430);
FORCEPROP 1 LAST MATERIAL X6S
J 0
(2700 4450);
DISPLAY 0.489362 (2700 4450);
PAINT SKYBLUE (2700 4450);
FORCEPROP 1 LAST TOLERANCE 20%
J 0
(2700 4500);
DISPLAY 0.489362 (2700 4500);
PAINT SKYBLUE (2700 4500);
FORCEPROP 1 LAST VALUE 22UF
J 0
(2700 4600);
DISPLAY 0.489362 (2700 4600);
PAINT SKYBLUE (2700 4600);
FORCEPROP 1 LAST VOLTAGE 4V
J 0
(2700 4550);
DISPLAY 0.489362 (2700 4550);
PAINT SKYBLUE (2700 4550);
FORCEPROP 1 LAST PACK_TYPE C0402
J 0
(2700 4350);
DISPLAY 0.489362 (2700 4350);
PAINT SKYBLUE (2700 4350);
FORCEPROP 2 LAST CDS_LIB pure_quanta
J 0
(2650 4550);
PAINT MONO (2650 4550);
DISPLAY INVISIBLE (2650 4550);
FORCEPROP 1 LAST PATH I65
J 0
(2700 4700);
DISPLAY 0.978723 (2700 4700);
PAINT WHITE (2700 4700);
DISPLAY INVISIBLE (2700 4700);
FORCEPROP 1 LAST PART_NUMBER CH622KMEB02
J 0
(2700 4400);
DISPLAY 0.489362 (2700 4400);
PAINT SKYBLUE (2700 4400);
DISPLAY INVISIBLE (2700 4400);
FORCEADD Q_CAP..1
(2200 5225);
FORCEPROP 1 LAST LOCATION C2436
J 0
(2250 5325);
DISPLAY 0.489362 (2250 5325);
PAINT SKYBLUE (2250 5325);
FORCEPROP 2 LAST $SEC 1
J 0
(2250 5425);
DISPLAY 0.680851 (2250 5425);
PAINT MONO (2250 5425);
DISPLAY INVISIBLE (2250 5425);
FORCEPROP 2 LAST CDS_SEC 1
J 0
(2250 5425);
DISPLAY 1.021277 (2250 5425);
DISPLAY INVISIBLE (2250 5425);
FORCEPROP 1 LASTPIN (2200 5325) $PN 1
J 0
(2210 5305);
DISPLAY 0.489362 (2210 5305);
FORCEPROP 1 LASTPIN (2200 5125) $PN 2
J 0
(2210 5105);
DISPLAY 0.489362 (2210 5105);
FORCEPROP 1 LAST MATERIAL X6S
J 0
(2250 5125);
DISPLAY 0.489362 (2250 5125);
PAINT SKYBLUE (2250 5125);
FORCEPROP 1 LAST TOLERANCE 20%
J 0
(2250 5175);
DISPLAY 0.489362 (2250 5175);
PAINT SKYBLUE (2250 5175);
FORCEPROP 1 LAST VALUE 22UF
J 0
(2250 5275);
DISPLAY 0.489362 (2250 5275);
PAINT SKYBLUE (2250 5275);
FORCEPROP 1 LAST VOLTAGE 4V
J 0
(2250 5225);
DISPLAY 0.489362 (2250 5225);
PAINT SKYBLUE (2250 5225);
FORCEPROP 1 LAST PACK_TYPE C0402
J 0
(2250 5025);
DISPLAY 0.489362 (2250 5025);
PAINT SKYBLUE (2250 5025);
FORCEPROP 2 LAST CDS_LIB pure_quanta
J 0
(2200 5225);
PAINT MONO (2200 5225);
DISPLAY INVISIBLE (2200 5225);
FORCEPROP 1 LAST PATH I66
J 0
(2250 5375);
DISPLAY 0.978723 (2250 5375);
PAINT WHITE (2250 5375);
DISPLAY INVISIBLE (2250 5375);
FORCEPROP 1 LAST PART_NUMBER CH622KMEB02
J 0
(2250 5075);
DISPLAY 0.489362 (2250 5075);
PAINT SKYBLUE (2250 5075);
DISPLAY INVISIBLE (2250 5075);
FORCEADD Q_CAP..1
(2650 5225);
FORCEPROP 1 LAST LOCATION C2443
J 0
(2700 5325);
DISPLAY 0.489362 (2700 5325);
PAINT SKYBLUE (2700 5325);
FORCEPROP 2 LAST $SEC 1
J 0
(2700 5425);
DISPLAY 0.680851 (2700 5425);
PAINT MONO (2700 5425);
DISPLAY INVISIBLE (2700 5425);
FORCEPROP 2 LAST CDS_SEC 1
J 0
(2700 5425);
DISPLAY 1.021277 (2700 5425);
DISPLAY INVISIBLE (2700 5425);
FORCEPROP 1 LASTPIN (2650 5325) $PN 1
J 0
(2660 5305);
DISPLAY 0.489362 (2660 5305);
FORCEPROP 1 LASTPIN (2650 5125) $PN 2
J 0
(2660 5105);
DISPLAY 0.489362 (2660 5105);
FORCEPROP 1 LAST MATERIAL X6S
J 0
(2700 5125);
DISPLAY 0.489362 (2700 5125);
PAINT SKYBLUE (2700 5125);
FORCEPROP 1 LAST TOLERANCE 20%
J 0
(2700 5175);
DISPLAY 0.489362 (2700 5175);
PAINT SKYBLUE (2700 5175);
FORCEPROP 1 LAST VALUE 22UF
J 0
(2700 5275);
DISPLAY 0.489362 (2700 5275);
PAINT SKYBLUE (2700 5275);
FORCEPROP 1 LAST VOLTAGE 4V
J 0
(2700 5225);
DISPLAY 0.489362 (2700 5225);
PAINT SKYBLUE (2700 5225);
FORCEPROP 1 LAST PACK_TYPE C0402
J 0
(2700 5025);
DISPLAY 0.489362 (2700 5025);
PAINT SKYBLUE (2700 5025);
FORCEPROP 2 LAST CDS_LIB pure_quanta
J 0
(2650 5225);
PAINT MONO (2650 5225);
DISPLAY INVISIBLE (2650 5225);
FORCEPROP 1 LAST PATH I67
J 0
(2700 5375);
DISPLAY 0.978723 (2700 5375);
PAINT WHITE (2700 5375);
DISPLAY INVISIBLE (2700 5375);
FORCEPROP 1 LAST PART_NUMBER CH622KMEB02
J 0
(2700 5075);
DISPLAY 0.489362 (2700 5075);
PAINT SKYBLUE (2700 5075);
DISPLAY INVISIBLE (2700 5075);
FORCEADD Q_CAP..1
(3100 5875);
FORCEPROP 1 LAST LOCATION C2449
J 0
(3150 5975);
DISPLAY 0.489362 (3150 5975);
PAINT SKYBLUE (3150 5975);
FORCEPROP 2 LAST $SEC 1
J 0
(3150 6075);
DISPLAY 0.680851 (3150 6075);
PAINT MONO (3150 6075);
DISPLAY INVISIBLE (3150 6075);
FORCEPROP 2 LAST CDS_SEC 1
J 0
(3150 6075);
DISPLAY 1.021277 (3150 6075);
DISPLAY INVISIBLE (3150 6075);
FORCEPROP 1 LASTPIN (3100 5975) $PN 1
J 0
(3110 5955);
DISPLAY 0.489362 (3110 5955);
FORCEPROP 1 LASTPIN (3100 5775) $PN 2
J 0
(3110 5755);
DISPLAY 0.489362 (3110 5755);
FORCEPROP 1 LAST MATERIAL X6S
J 0
(3150 5775);
DISPLAY 0.489362 (3150 5775);
PAINT SKYBLUE (3150 5775);
FORCEPROP 1 LAST TOLERANCE 20%
J 0
(3150 5825);
DISPLAY 0.489362 (3150 5825);
PAINT SKYBLUE (3150 5825);
FORCEPROP 1 LAST VALUE 22UF
J 0
(3150 5925);
DISPLAY 0.489362 (3150 5925);
PAINT SKYBLUE (3150 5925);
FORCEPROP 1 LAST VOLTAGE 4V
J 0
(3150 5875);
DISPLAY 0.489362 (3150 5875);
PAINT SKYBLUE (3150 5875);
FORCEPROP 1 LAST PACK_TYPE C0402
J 0
(3150 5675);
DISPLAY 0.489362 (3150 5675);
PAINT SKYBLUE (3150 5675);
FORCEPROP 2 LAST CDS_LIB pure_quanta
J 0
(3100 5875);
PAINT MONO (3100 5875);
DISPLAY INVISIBLE (3100 5875);
FORCEPROP 1 LAST PATH I68
J 0
(3150 6025);
DISPLAY 0.978723 (3150 6025);
PAINT WHITE (3150 6025);
DISPLAY INVISIBLE (3150 6025);
FORCEPROP 1 LAST PART_NUMBER CH622KMEB02
J 0
(3150 5725);
DISPLAY 0.489362 (3150 5725);
PAINT SKYBLUE (3150 5725);
DISPLAY INVISIBLE (3150 5725);
FORCEADD Q_CAP..1
(3100 5225);
FORCEPROP 1 LAST LOCATION C2450
J 0
(3150 5325);
DISPLAY 0.489362 (3150 5325);
PAINT SKYBLUE (3150 5325);
FORCEPROP 2 LAST $SEC 1
J 0
(3150 5425);
DISPLAY 0.680851 (3150 5425);
PAINT MONO (3150 5425);
DISPLAY INVISIBLE (3150 5425);
FORCEPROP 2 LAST CDS_SEC 1
J 0
(3150 5425);
DISPLAY 1.021277 (3150 5425);
DISPLAY INVISIBLE (3150 5425);
FORCEPROP 1 LASTPIN (3100 5325) $PN 1
J 0
(3110 5305);
DISPLAY 0.489362 (3110 5305);
FORCEPROP 1 LASTPIN (3100 5125) $PN 2
J 0
(3110 5105);
DISPLAY 0.489362 (3110 5105);
FORCEPROP 1 LAST MATERIAL X6S
J 0
(3150 5125);
DISPLAY 0.489362 (3150 5125);
PAINT SKYBLUE (3150 5125);
FORCEPROP 1 LAST TOLERANCE 20%
J 0
(3150 5175);
DISPLAY 0.489362 (3150 5175);
PAINT SKYBLUE (3150 5175);
FORCEPROP 1 LAST VALUE 22UF
J 0
(3150 5275);
DISPLAY 0.489362 (3150 5275);
PAINT SKYBLUE (3150 5275);
FORCEPROP 1 LAST VOLTAGE 4V
J 0
(3150 5225);
DISPLAY 0.489362 (3150 5225);
PAINT SKYBLUE (3150 5225);
FORCEPROP 1 LAST PACK_TYPE C0402
J 0
(3150 5025);
DISPLAY 0.489362 (3150 5025);
PAINT SKYBLUE (3150 5025);
FORCEPROP 2 LAST CDS_LIB pure_quanta
J 0
(3100 5225);
PAINT MONO (3100 5225);
DISPLAY INVISIBLE (3100 5225);
FORCEPROP 1 LAST PATH I69
J 0
(3150 5375);
DISPLAY 0.978723 (3150 5375);
PAINT WHITE (3150 5375);
DISPLAY INVISIBLE (3150 5375);
FORCEPROP 1 LAST PART_NUMBER CH622KMEB02
J 0
(3150 5075);
DISPLAY 0.489362 (3150 5075);
PAINT SKYBLUE (3150 5075);
DISPLAY INVISIBLE (3150 5075);
FORCEADD Q_CAP..1
(1300 1800);
FORCEPROP 1 LAST LOCATION C2427
J 0
(1350 1900);
DISPLAY 0.489362 (1350 1900);
PAINT SKYBLUE (1350 1900);
FORCEPROP 2 LAST $SEC 1
J 0
(1350 2000);
DISPLAY 0.680851 (1350 2000);
PAINT MONO (1350 2000);
DISPLAY INVISIBLE (1350 2000);
FORCEPROP 2 LAST CDS_SEC 1
J 0
(1350 2000);
DISPLAY 1.021277 (1350 2000);
DISPLAY INVISIBLE (1350 2000);
FORCEPROP 1 LASTPIN (1300 1900) $PN 1
J 0
(1310 1880);
DISPLAY 0.489362 (1310 1880);
FORCEPROP 1 LASTPIN (1300 1700) $PN 2
J 0
(1310 1680);
DISPLAY 0.489362 (1310 1680);
FORCEPROP 1 LAST MATERIAL X6S
J 0
(1350 1700);
DISPLAY 0.489362 (1350 1700);
PAINT SKYBLUE (1350 1700);
FORCEPROP 1 LAST TOLERANCE 20%
J 0
(1350 1750);
DISPLAY 0.489362 (1350 1750);
PAINT SKYBLUE (1350 1750);
FORCEPROP 1 LAST VALUE 22UF
J 0
(1350 1850);
DISPLAY 0.489362 (1350 1850);
PAINT SKYBLUE (1350 1850);
FORCEPROP 1 LAST VOLTAGE 4V
J 0
(1350 1800);
DISPLAY 0.489362 (1350 1800);
PAINT SKYBLUE (1350 1800);
FORCEPROP 1 LAST PACK_TYPE C0402
J 0
(1350 1600);
DISPLAY 0.489362 (1350 1600);
PAINT SKYBLUE (1350 1600);
FORCEPROP 2 LAST CDS_LIB pure_quanta
J 0
(1300 1800);
PAINT MONO (1300 1800);
DISPLAY INVISIBLE (1300 1800);
FORCEPROP 1 LAST PATH I7
J 0
(1350 1950);
DISPLAY 0.978723 (1350 1950);
PAINT WHITE (1350 1950);
DISPLAY INVISIBLE (1350 1950);
FORCEPROP 1 LAST PART_NUMBER CH622KMEB02
J 0
(1350 1650);
DISPLAY 0.489362 (1350 1650);
PAINT SKYBLUE (1350 1650);
DISPLAY INVISIBLE (1350 1650);
FORCEADD Q_CAP..1
(3100 4550);
FORCEPROP 1 LAST LOCATION C2451
J 0
(3150 4650);
DISPLAY 0.489362 (3150 4650);
PAINT SKYBLUE (3150 4650);
FORCEPROP 2 LAST $SEC 1
J 0
(3150 4750);
DISPLAY 0.680851 (3150 4750);
PAINT MONO (3150 4750);
DISPLAY INVISIBLE (3150 4750);
FORCEPROP 2 LAST CDS_SEC 1
J 0
(3150 4750);
DISPLAY 1.021277 (3150 4750);
DISPLAY INVISIBLE (3150 4750);
FORCEPROP 1 LASTPIN (3100 4650) $PN 1
J 0
(3110 4630);
DISPLAY 0.489362 (3110 4630);
FORCEPROP 1 LASTPIN (3100 4450) $PN 2
J 0
(3110 4430);
DISPLAY 0.489362 (3110 4430);
FORCEPROP 1 LAST MATERIAL X6S
J 0
(3150 4450);
DISPLAY 0.489362 (3150 4450);
PAINT SKYBLUE (3150 4450);
FORCEPROP 1 LAST TOLERANCE 20%
J 0
(3150 4500);
DISPLAY 0.489362 (3150 4500);
PAINT SKYBLUE (3150 4500);
FORCEPROP 1 LAST VALUE 22UF
J 0
(3150 4600);
DISPLAY 0.489362 (3150 4600);
PAINT SKYBLUE (3150 4600);
FORCEPROP 1 LAST VOLTAGE 4V
J 0
(3150 4550);
DISPLAY 0.489362 (3150 4550);
PAINT SKYBLUE (3150 4550);
FORCEPROP 1 LAST PACK_TYPE C0402
J 0
(3150 4350);
DISPLAY 0.489362 (3150 4350);
PAINT SKYBLUE (3150 4350);
FORCEPROP 2 LAST CDS_LIB pure_quanta
J 0
(3100 4550);
PAINT MONO (3100 4550);
DISPLAY INVISIBLE (3100 4550);
FORCEPROP 1 LAST PATH I70
J 0
(3150 4700);
DISPLAY 0.978723 (3150 4700);
PAINT WHITE (3150 4700);
DISPLAY INVISIBLE (3150 4700);
FORCEPROP 1 LAST PART_NUMBER CH622KMEB02
J 0
(3150 4400);
DISPLAY 0.489362 (3150 4400);
PAINT SKYBLUE (3150 4400);
DISPLAY INVISIBLE (3150 4400);
FORCEADD Q_CAP..1
(3550 4550);
FORCEPROP 1 LAST LOCATION C2458
J 0
(3600 4650);
DISPLAY 0.489362 (3600 4650);
PAINT SKYBLUE (3600 4650);
FORCEPROP 2 LAST $SEC 1
J 0
(3600 4750);
DISPLAY 0.680851 (3600 4750);
PAINT MONO (3600 4750);
DISPLAY INVISIBLE (3600 4750);
FORCEPROP 2 LAST CDS_SEC 1
J 0
(3600 4750);
DISPLAY 1.021277 (3600 4750);
DISPLAY INVISIBLE (3600 4750);
FORCEPROP 1 LASTPIN (3550 4650) $PN 1
J 0
(3560 4630);
DISPLAY 0.489362 (3560 4630);
FORCEPROP 1 LASTPIN (3550 4450) $PN 2
J 0
(3560 4430);
DISPLAY 0.489362 (3560 4430);
FORCEPROP 1 LAST MATERIAL X6S
J 0
(3600 4450);
DISPLAY 0.489362 (3600 4450);
PAINT SKYBLUE (3600 4450);
FORCEPROP 1 LAST TOLERANCE 20%
J 0
(3600 4500);
DISPLAY 0.489362 (3600 4500);
PAINT SKYBLUE (3600 4500);
FORCEPROP 1 LAST VALUE 22UF
J 0
(3600 4600);
DISPLAY 0.489362 (3600 4600);
PAINT SKYBLUE (3600 4600);
FORCEPROP 1 LAST VOLTAGE 4V
J 0
(3600 4550);
DISPLAY 0.489362 (3600 4550);
PAINT SKYBLUE (3600 4550);
FORCEPROP 1 LAST PACK_TYPE C0402
J 0
(3600 4350);
DISPLAY 0.489362 (3600 4350);
PAINT SKYBLUE (3600 4350);
FORCEPROP 2 LAST CDS_LIB pure_quanta
J 0
(3550 4550);
PAINT MONO (3550 4550);
DISPLAY INVISIBLE (3550 4550);
FORCEPROP 1 LAST PATH I71
J 0
(3600 4700);
DISPLAY 0.978723 (3600 4700);
PAINT WHITE (3600 4700);
DISPLAY INVISIBLE (3600 4700);
FORCEPROP 1 LAST PART_NUMBER CH622KMEB02
J 0
(3600 4400);
DISPLAY 0.489362 (3600 4400);
PAINT SKYBLUE (3600 4400);
DISPLAY INVISIBLE (3600 4400);
FORCEADD Q_CAP..1
(4000 4550);
FORCEPROP 1 LAST LOCATION C2465
J 0
(4050 4650);
DISPLAY 0.489362 (4050 4650);
PAINT SKYBLUE (4050 4650);
FORCEPROP 2 LAST $SEC 1
J 0
(4050 4750);
DISPLAY 0.680851 (4050 4750);
PAINT MONO (4050 4750);
DISPLAY INVISIBLE (4050 4750);
FORCEPROP 2 LAST CDS_SEC 1
J 0
(4050 4750);
DISPLAY 1.021277 (4050 4750);
DISPLAY INVISIBLE (4050 4750);
FORCEPROP 1 LASTPIN (4000 4650) $PN 1
J 0
(4010 4630);
DISPLAY 0.489362 (4010 4630);
FORCEPROP 1 LASTPIN (4000 4450) $PN 2
J 0
(4010 4430);
DISPLAY 0.489362 (4010 4430);
FORCEPROP 1 LAST MATERIAL X6S
J 0
(4050 4450);
DISPLAY 0.489362 (4050 4450);
PAINT SKYBLUE (4050 4450);
FORCEPROP 1 LAST TOLERANCE 20%
J 0
(4050 4500);
DISPLAY 0.489362 (4050 4500);
PAINT SKYBLUE (4050 4500);
FORCEPROP 1 LAST VALUE 22UF
J 0
(4050 4600);
DISPLAY 0.489362 (4050 4600);
PAINT SKYBLUE (4050 4600);
FORCEPROP 1 LAST VOLTAGE 4V
J 0
(4050 4550);
DISPLAY 0.489362 (4050 4550);
PAINT SKYBLUE (4050 4550);
FORCEPROP 1 LAST PACK_TYPE C0402
J 0
(4050 4350);
DISPLAY 0.489362 (4050 4350);
PAINT SKYBLUE (4050 4350);
FORCEPROP 2 LAST CDS_LIB pure_quanta
J 0
(4000 4550);
PAINT MONO (4000 4550);
DISPLAY INVISIBLE (4000 4550);
FORCEPROP 1 LAST PATH I72
J 0
(4050 4700);
DISPLAY 0.978723 (4050 4700);
PAINT WHITE (4050 4700);
DISPLAY INVISIBLE (4050 4700);
FORCEPROP 1 LAST PART_NUMBER CH622KMEB02
J 0
(4050 4400);
DISPLAY 0.489362 (4050 4400);
PAINT SKYBLUE (4050 4400);
DISPLAY INVISIBLE (4050 4400);
FORCEADD Q_CAP..1
(3550 5225);
FORCEPROP 1 LAST LOCATION C2457
J 0
(3600 5325);
DISPLAY 0.489362 (3600 5325);
PAINT SKYBLUE (3600 5325);
FORCEPROP 2 LAST $SEC 1
J 0
(3600 5425);
DISPLAY 0.680851 (3600 5425);
PAINT MONO (3600 5425);
DISPLAY INVISIBLE (3600 5425);
FORCEPROP 2 LAST CDS_SEC 1
J 0
(3600 5425);
DISPLAY 1.021277 (3600 5425);
DISPLAY INVISIBLE (3600 5425);
FORCEPROP 1 LASTPIN (3550 5325) $PN 1
J 0
(3560 5305);
DISPLAY 0.489362 (3560 5305);
FORCEPROP 1 LASTPIN (3550 5125) $PN 2
J 0
(3560 5105);
DISPLAY 0.489362 (3560 5105);
FORCEPROP 1 LAST MATERIAL X6S
J 0
(3600 5125);
DISPLAY 0.489362 (3600 5125);
PAINT SKYBLUE (3600 5125);
FORCEPROP 1 LAST TOLERANCE 20%
J 0
(3600 5175);
DISPLAY 0.489362 (3600 5175);
PAINT SKYBLUE (3600 5175);
FORCEPROP 1 LAST VALUE 22UF
J 0
(3600 5275);
DISPLAY 0.489362 (3600 5275);
PAINT SKYBLUE (3600 5275);
FORCEPROP 1 LAST VOLTAGE 4V
J 0
(3600 5225);
DISPLAY 0.489362 (3600 5225);
PAINT SKYBLUE (3600 5225);
FORCEPROP 1 LAST PACK_TYPE C0402
J 0
(3600 5025);
DISPLAY 0.489362 (3600 5025);
PAINT SKYBLUE (3600 5025);
FORCEPROP 2 LAST CDS_LIB pure_quanta
J 0
(3550 5225);
PAINT MONO (3550 5225);
DISPLAY INVISIBLE (3550 5225);
FORCEPROP 1 LAST PATH I73
J 0
(3600 5375);
DISPLAY 0.978723 (3600 5375);
PAINT WHITE (3600 5375);
DISPLAY INVISIBLE (3600 5375);
FORCEPROP 1 LAST PART_NUMBER CH622KMEB02
J 0
(3600 5075);
DISPLAY 0.489362 (3600 5075);
PAINT SKYBLUE (3600 5075);
DISPLAY INVISIBLE (3600 5075);
FORCEADD Q_CAP..1
(3550 5875);
FORCEPROP 1 LAST LOCATION C2456
J 0
(3600 5975);
DISPLAY 0.489362 (3600 5975);
PAINT SKYBLUE (3600 5975);
FORCEPROP 2 LAST $SEC 1
J 0
(3600 6075);
DISPLAY 0.680851 (3600 6075);
PAINT MONO (3600 6075);
DISPLAY INVISIBLE (3600 6075);
FORCEPROP 2 LAST CDS_SEC 1
J 0
(3600 6075);
DISPLAY 1.021277 (3600 6075);
DISPLAY INVISIBLE (3600 6075);
FORCEPROP 1 LASTPIN (3550 5975) $PN 1
J 0
(3560 5955);
DISPLAY 0.489362 (3560 5955);
FORCEPROP 1 LASTPIN (3550 5775) $PN 2
J 0
(3560 5755);
DISPLAY 0.489362 (3560 5755);
FORCEPROP 1 LAST MATERIAL X6S
J 0
(3600 5775);
DISPLAY 0.489362 (3600 5775);
PAINT SKYBLUE (3600 5775);
FORCEPROP 1 LAST TOLERANCE 20%
J 0
(3600 5825);
DISPLAY 0.489362 (3600 5825);
PAINT SKYBLUE (3600 5825);
FORCEPROP 1 LAST VALUE 22UF
J 0
(3600 5925);
DISPLAY 0.489362 (3600 5925);
PAINT SKYBLUE (3600 5925);
FORCEPROP 1 LAST VOLTAGE 4V
J 0
(3600 5875);
DISPLAY 0.489362 (3600 5875);
PAINT SKYBLUE (3600 5875);
FORCEPROP 1 LAST PACK_TYPE C0402
J 0
(3600 5675);
DISPLAY 0.489362 (3600 5675);
PAINT SKYBLUE (3600 5675);
FORCEPROP 2 LAST CDS_LIB pure_quanta
J 0
(3550 5875);
PAINT MONO (3550 5875);
DISPLAY INVISIBLE (3550 5875);
FORCEPROP 1 LAST PATH I74
J 0
(3600 6025);
DISPLAY 0.978723 (3600 6025);
PAINT WHITE (3600 6025);
DISPLAY INVISIBLE (3600 6025);
FORCEPROP 1 LAST PART_NUMBER CH622KMEB02
J 0
(3600 5725);
DISPLAY 0.489362 (3600 5725);
PAINT SKYBLUE (3600 5725);
DISPLAY INVISIBLE (3600 5725);
FORCEADD Q_CAP..1
(4000 5225);
FORCEPROP 1 LAST LOCATION C2464
J 0
(4050 5325);
DISPLAY 0.489362 (4050 5325);
PAINT SKYBLUE (4050 5325);
FORCEPROP 2 LAST $SEC 1
J 0
(4050 5425);
DISPLAY 0.680851 (4050 5425);
PAINT MONO (4050 5425);
DISPLAY INVISIBLE (4050 5425);
FORCEPROP 2 LAST CDS_SEC 1
J 0
(4050 5425);
DISPLAY 1.021277 (4050 5425);
DISPLAY INVISIBLE (4050 5425);
FORCEPROP 1 LASTPIN (4000 5325) $PN 1
J 0
(4010 5305);
DISPLAY 0.489362 (4010 5305);
FORCEPROP 1 LASTPIN (4000 5125) $PN 2
J 0
(4010 5105);
DISPLAY 0.489362 (4010 5105);
FORCEPROP 1 LAST MATERIAL X6S
J 0
(4050 5125);
DISPLAY 0.489362 (4050 5125);
PAINT SKYBLUE (4050 5125);
FORCEPROP 1 LAST TOLERANCE 20%
J 0
(4050 5175);
DISPLAY 0.489362 (4050 5175);
PAINT SKYBLUE (4050 5175);
FORCEPROP 1 LAST VALUE 22UF
J 0
(4050 5275);
DISPLAY 0.489362 (4050 5275);
PAINT SKYBLUE (4050 5275);
FORCEPROP 1 LAST VOLTAGE 4V
J 0
(4050 5225);
DISPLAY 0.489362 (4050 5225);
PAINT SKYBLUE (4050 5225);
FORCEPROP 1 LAST PACK_TYPE C0402
J 0
(4050 5025);
DISPLAY 0.489362 (4050 5025);
PAINT SKYBLUE (4050 5025);
FORCEPROP 2 LAST CDS_LIB pure_quanta
J 0
(4000 5225);
PAINT MONO (4000 5225);
DISPLAY INVISIBLE (4000 5225);
FORCEPROP 1 LAST PATH I75
J 0
(4050 5375);
DISPLAY 0.978723 (4050 5375);
PAINT WHITE (4050 5375);
DISPLAY INVISIBLE (4050 5375);
FORCEPROP 1 LAST PART_NUMBER CH622KMEB02
J 0
(4050 5075);
DISPLAY 0.489362 (4050 5075);
PAINT SKYBLUE (4050 5075);
DISPLAY INVISIBLE (4050 5075);
FORCEADD Q_CAP..1
(4000 5875);
FORCEPROP 1 LAST LOCATION C2463
J 0
(4050 5975);
DISPLAY 0.489362 (4050 5975);
PAINT SKYBLUE (4050 5975);
FORCEPROP 2 LAST $SEC 1
J 0
(4050 6075);
DISPLAY 0.680851 (4050 6075);
PAINT MONO (4050 6075);
DISPLAY INVISIBLE (4050 6075);
FORCEPROP 2 LAST CDS_SEC 1
J 0
(4050 6075);
DISPLAY 1.021277 (4050 6075);
DISPLAY INVISIBLE (4050 6075);
FORCEPROP 1 LASTPIN (4000 5975) $PN 1
J 0
(4010 5955);
DISPLAY 0.489362 (4010 5955);
FORCEPROP 1 LASTPIN (4000 5775) $PN 2
J 0
(4010 5755);
DISPLAY 0.489362 (4010 5755);
FORCEPROP 1 LAST MATERIAL X6S
J 0
(4050 5775);
DISPLAY 0.489362 (4050 5775);
PAINT SKYBLUE (4050 5775);
FORCEPROP 1 LAST TOLERANCE 20%
J 0
(4050 5825);
DISPLAY 0.489362 (4050 5825);
PAINT SKYBLUE (4050 5825);
FORCEPROP 1 LAST VALUE 22UF
J 0
(4050 5925);
DISPLAY 0.489362 (4050 5925);
PAINT SKYBLUE (4050 5925);
FORCEPROP 1 LAST VOLTAGE 4V
J 0
(4050 5875);
DISPLAY 0.489362 (4050 5875);
PAINT SKYBLUE (4050 5875);
FORCEPROP 1 LAST PACK_TYPE C0402
J 0
(4050 5675);
DISPLAY 0.489362 (4050 5675);
PAINT SKYBLUE (4050 5675);
FORCEPROP 2 LAST CDS_LIB pure_quanta
J 0
(4000 5875);
PAINT MONO (4000 5875);
DISPLAY INVISIBLE (4000 5875);
FORCEPROP 1 LAST PATH I76
J 0
(4050 6025);
DISPLAY 0.978723 (4050 6025);
PAINT WHITE (4050 6025);
DISPLAY INVISIBLE (4050 6025);
FORCEPROP 1 LAST PART_NUMBER CH622KMEB02
J 0
(4050 5725);
DISPLAY 0.489362 (4050 5725);
PAINT SKYBLUE (4050 5725);
DISPLAY INVISIBLE (4050 5725);
FORCEADD Q_CAP..1
(5000 775);
FORCEPROP 1 LAST LOCATION C3919
J 0
(5050 875);
DISPLAY 0.489362 (5050 875);
PAINT SKYBLUE (5050 875);
FORCEPROP 2 LAST $SEC 1
J 0
(5050 975);
DISPLAY 0.680851 (5050 975);
PAINT MONO (5050 975);
DISPLAY INVISIBLE (5050 975);
FORCEPROP 2 LAST CDS_SEC 1
J 0
(5050 975);
DISPLAY 1.021277 (5050 975);
DISPLAY INVISIBLE (5050 975);
FORCEPROP 1 LASTPIN (5000 875) $PN 1
J 0
(5010 855);
DISPLAY 0.489362 (5010 855);
FORCEPROP 1 LASTPIN (5000 675) $PN 2
J 0
(5010 655);
DISPLAY 0.489362 (5010 655);
FORCEPROP 1 LAST MATERIAL X6S
J 0
(5050 675);
DISPLAY 0.489362 (5050 675);
PAINT SKYBLUE (5050 675);
FORCEPROP 1 LAST TOLERANCE 20%
J 0
(5050 725);
DISPLAY 0.489362 (5050 725);
PAINT SKYBLUE (5050 725);
FORCEPROP 1 LAST VALUE 22UF
J 0
(5050 825);
DISPLAY 0.489362 (5050 825);
PAINT SKYBLUE (5050 825);
FORCEPROP 1 LAST VOLTAGE 4V
J 0
(5050 775);
DISPLAY 0.489362 (5050 775);
PAINT SKYBLUE (5050 775);
FORCEPROP 1 LAST PACK_TYPE C0402
J 0
(5050 575);
DISPLAY 0.489362 (5050 575);
PAINT SKYBLUE (5050 575);
FORCEPROP 2 LAST CDS_LIB pure_quanta
J 0
(5000 775);
PAINT MONO (5000 775);
DISPLAY INVISIBLE (5000 775);
FORCEPROP 1 LAST PATH I77
J 0
(5050 925);
DISPLAY 0.978723 (5050 925);
PAINT WHITE (5050 925);
DISPLAY INVISIBLE (5050 925);
FORCEPROP 1 LAST PART_NUMBER CH622KMEB02
J 0
(5050 625);
DISPLAY 0.489362 (5050 625);
PAINT SKYBLUE (5050 625);
DISPLAY INVISIBLE (5050 625);
FORCEADD UNIVERSAL_GND..1
(4400 1425);
FORCEPROP 3 LASTPIN (4400 1475) SIG_NAME GND\g
J 0
(4410 1485);
DISPLAY 0.659574 (4410 1485);
PAINT MONO (4410 1485);
DISPLAY INVISIBLE (4410 1485);
FORCEPROP 2 LAST CDS_LIB pure_quanta_power
J 0
(4400 1425);
PAINT MONO (4400 1425);
DISPLAY INVISIBLE (4400 1425);
FORCEPROP 1 LAST HDL_POWER GND
J 1
(4425 1350);
DISPLAY 0.872340 (4425 1350);
PAINT GREEN (4425 1350);
DISPLAY INVISIBLE (4425 1350);
FORCEPROP 1 LAST PATH I78
J 0
(4475 1425);
DISPLAY 0.872340 (4475 1425);
PAINT AQUA (4475 1425);
DISPLAY INVISIBLE (4475 1425);
FORCEADD Q_CAP..1
(4400 1800);
FORCEPROP 1 LAST LOCATION C2476
J 0
(4450 1900);
DISPLAY 0.489362 (4450 1900);
PAINT SKYBLUE (4450 1900);
FORCEPROP 2 LAST $SEC 1
J 0
(4450 2000);
DISPLAY 0.680851 (4450 2000);
PAINT MONO (4450 2000);
DISPLAY INVISIBLE (4450 2000);
FORCEPROP 2 LAST CDS_SEC 1
J 0
(4450 2000);
DISPLAY 1.021277 (4450 2000);
DISPLAY INVISIBLE (4450 2000);
FORCEPROP 1 LASTPIN (4400 1900) $PN 1
J 0
(4410 1880);
DISPLAY 0.489362 (4410 1880);
FORCEPROP 1 LASTPIN (4400 1700) $PN 2
J 0
(4410 1680);
DISPLAY 0.489362 (4410 1680);
FORCEPROP 1 LAST MATERIAL X6S
J 0
(4450 1700);
DISPLAY 0.489362 (4450 1700);
PAINT SKYBLUE (4450 1700);
FORCEPROP 1 LAST TOLERANCE 20%
J 0
(4450 1750);
DISPLAY 0.489362 (4450 1750);
PAINT SKYBLUE (4450 1750);
FORCEPROP 1 LAST VALUE 22UF
J 0
(4450 1850);
DISPLAY 0.489362 (4450 1850);
PAINT SKYBLUE (4450 1850);
FORCEPROP 1 LAST VOLTAGE 4V
J 0
(4450 1800);
DISPLAY 0.489362 (4450 1800);
PAINT SKYBLUE (4450 1800);
FORCEPROP 1 LAST PACK_TYPE C0402
J 0
(4450 1600);
DISPLAY 0.489362 (4450 1600);
PAINT SKYBLUE (4450 1600);
FORCEPROP 2 LAST CDS_LIB pure_quanta
J 0
(4400 1800);
PAINT MONO (4400 1800);
DISPLAY INVISIBLE (4400 1800);
FORCEPROP 1 LAST PATH I79
J 0
(4450 1950);
DISPLAY 0.978723 (4450 1950);
PAINT WHITE (4450 1950);
DISPLAY INVISIBLE (4450 1950);
FORCEPROP 1 LAST PART_NUMBER CH622KMEB02
J 0
(4450 1650);
DISPLAY 0.489362 (4450 1650);
PAINT SKYBLUE (4450 1650);
DISPLAY INVISIBLE (4450 1650);
FORCEADD Q_CAP..1
(1750 1075);
FORCEPROP 1 LAST LOCATION C3915
J 0
(1800 1175);
DISPLAY 0.489362 (1800 1175);
PAINT SKYBLUE (1800 1175);
FORCEPROP 2 LAST $SEC 1
J 0
(1800 1275);
DISPLAY 0.680851 (1800 1275);
PAINT MONO (1800 1275);
DISPLAY INVISIBLE (1800 1275);
FORCEPROP 2 LAST CDS_SEC 1
J 0
(1800 1275);
DISPLAY 1.021277 (1800 1275);
DISPLAY INVISIBLE (1800 1275);
FORCEPROP 1 LASTPIN (1750 1175) $PN 1
J 0
(1760 1155);
DISPLAY 0.489362 (1760 1155);
FORCEPROP 1 LASTPIN (1750 975) $PN 2
J 0
(1760 955);
DISPLAY 0.489362 (1760 955);
FORCEPROP 1 LAST MATERIAL X6S
J 0
(1800 975);
DISPLAY 0.489362 (1800 975);
PAINT SKYBLUE (1800 975);
FORCEPROP 1 LAST TOLERANCE 20%
J 0
(1800 1025);
DISPLAY 0.489362 (1800 1025);
PAINT SKYBLUE (1800 1025);
FORCEPROP 1 LAST VALUE 22UF
J 0
(1800 1125);
DISPLAY 0.489362 (1800 1125);
PAINT SKYBLUE (1800 1125);
FORCEPROP 1 LAST VOLTAGE 4V
J 0
(1800 1075);
DISPLAY 0.489362 (1800 1075);
PAINT SKYBLUE (1800 1075);
FORCEPROP 1 LAST PACK_TYPE C0402
J 0
(1800 875);
DISPLAY 0.489362 (1800 875);
PAINT SKYBLUE (1800 875);
FORCEPROP 2 LAST CDS_LIB pure_quanta
J 0
(1750 1075);
PAINT MONO (1750 1075);
DISPLAY INVISIBLE (1750 1075);
FORCEPROP 1 LAST PATH I8
J 0
(1800 1225);
DISPLAY 0.978723 (1800 1225);
PAINT WHITE (1800 1225);
DISPLAY INVISIBLE (1800 1225);
FORCEPROP 1 LAST PART_NUMBER CH622KMEB02
J 0
(1800 925);
DISPLAY 0.489362 (1800 925);
PAINT SKYBLUE (1800 925);
DISPLAY INVISIBLE (1800 925);
FORCEADD UNIVERSAL_POWER..1
(5000 1050);
FORCEPROP 3 LASTPIN (5000 1000) SIG_NAME PVDD11_S3_P1\g
J 0
(5010 1010);
DISPLAY 0.659574 (5010 1010);
PAINT MONO (5010 1010);
DISPLAY INVISIBLE (5010 1010);
FORCEPROP 1 LAST HDL_POWER PVDD11_S3_P1
J 1
(5000 1100);
DISPLAY 0.489362 (5000 1100);
PAINT GREEN (5000 1100);
FORCEPROP 2 LAST CDS_LIB pure_quanta_power
J 0
(5000 1050);
DISPLAY INVISIBLE (5000 1050);
FORCEPROP 1 LAST PATH I80
J 0
(5050 1075);
DISPLAY 0.872340 (5050 1075);
PAINT AQUA (5050 1075);
DISPLAY INVISIBLE (5050 1075);
FORCEADD Q_CAP..1
(5000 1375);
FORCEPROP 1 LAST LOCATION C2483
J 0
(5050 1475);
DISPLAY 0.489362 (5050 1475);
PAINT SKYBLUE (5050 1475);
FORCEPROP 2 LAST $SEC 1
J 0
(5050 1575);
DISPLAY 0.680851 (5050 1575);
PAINT MONO (5050 1575);
DISPLAY INVISIBLE (5050 1575);
FORCEPROP 2 LAST CDS_SEC 1
J 0
(5050 1575);
DISPLAY 1.021277 (5050 1575);
DISPLAY INVISIBLE (5050 1575);
FORCEPROP 1 LASTPIN (5000 1475) $PN 1
J 0
(5010 1455);
DISPLAY 0.489362 (5010 1455);
FORCEPROP 1 LASTPIN (5000 1275) $PN 2
J 0
(5010 1255);
DISPLAY 0.489362 (5010 1255);
FORCEPROP 1 LAST MATERIAL X6S
J 0
(5050 1275);
DISPLAY 0.489362 (5050 1275);
PAINT SKYBLUE (5050 1275);
FORCEPROP 1 LAST TOLERANCE 20%
J 0
(5050 1325);
DISPLAY 0.489362 (5050 1325);
PAINT SKYBLUE (5050 1325);
FORCEPROP 1 LAST VALUE 22UF
J 0
(5050 1425);
DISPLAY 0.489362 (5050 1425);
PAINT SKYBLUE (5050 1425);
FORCEPROP 1 LAST VOLTAGE 4V
J 0
(5050 1375);
DISPLAY 0.489362 (5050 1375);
PAINT SKYBLUE (5050 1375);
FORCEPROP 1 LAST PACK_TYPE C0402
J 0
(5050 1175);
DISPLAY 0.489362 (5050 1175);
PAINT SKYBLUE (5050 1175);
FORCEPROP 2 LAST CDS_LIB pure_quanta
J 0
(5000 1375);
PAINT MONO (5000 1375);
DISPLAY INVISIBLE (5000 1375);
FORCEPROP 1 LAST PATH I81
J 0
(5050 1525);
DISPLAY 0.978723 (5050 1525);
PAINT WHITE (5050 1525);
DISPLAY INVISIBLE (5050 1525);
FORCEPROP 1 LAST PART_NUMBER CH622KMEB02
J 0
(5050 1225);
DISPLAY 0.489362 (5050 1225);
PAINT SKYBLUE (5050 1225);
DISPLAY INVISIBLE (5050 1225);
FORCEADD UNIVERSAL_POWER..1
(5000 1650);
FORCEPROP 3 LASTPIN (5000 1600) SIG_NAME PVDD11_S3_P1\g
J 0
(5010 1610);
DISPLAY 0.659574 (5010 1610);
PAINT MONO (5010 1610);
DISPLAY INVISIBLE (5010 1610);
FORCEPROP 1 LAST HDL_POWER PVDD11_S3_P1
J 1
(5000 1700);
DISPLAY 0.489362 (5000 1700);
PAINT GREEN (5000 1700);
FORCEPROP 2 LAST CDS_LIB pure_quanta_power
J 0
(5000 1650);
DISPLAY INVISIBLE (5000 1650);
FORCEPROP 1 LAST PATH I82
J 0
(5050 1675);
DISPLAY 0.872340 (5050 1675);
PAINT AQUA (5050 1675);
DISPLAY INVISIBLE (5050 1675);
FORCEADD UNIVERSAL_GND..1
(5450 450);
FORCEPROP 3 LASTPIN (5450 500) SIG_NAME GND\g
J 0
(5460 510);
DISPLAY 0.659574 (5460 510);
PAINT MONO (5460 510);
DISPLAY INVISIBLE (5460 510);
FORCEPROP 2 LAST CDS_LIB pure_quanta_power
J 0
(5450 450);
DISPLAY INVISIBLE (5450 450);
FORCEPROP 1 LAST HDL_POWER GND
J 1
(5475 375);
DISPLAY 0.872340 (5475 375);
PAINT GREEN (5475 375);
DISPLAY INVISIBLE (5475 375);
FORCEPROP 1 LAST PATH I83
J 0
(5525 450);
DISPLAY 0.872340 (5525 450);
PAINT AQUA (5525 450);
DISPLAY INVISIBLE (5525 450);
FORCEADD Q_CAP..1
(5450 775);
FORCEPROP 1 LAST LOCATION C3920
J 0
(5500 875);
DISPLAY 0.489362 (5500 875);
PAINT SKYBLUE (5500 875);
FORCEPROP 2 LAST $SEC 1
J 0
(5500 975);
DISPLAY 0.680851 (5500 975);
PAINT MONO (5500 975);
DISPLAY INVISIBLE (5500 975);
FORCEPROP 2 LAST CDS_SEC 1
J 0
(5500 975);
DISPLAY 1.021277 (5500 975);
DISPLAY INVISIBLE (5500 975);
FORCEPROP 1 LASTPIN (5450 875) $PN 1
J 0
(5460 855);
DISPLAY 0.489362 (5460 855);
FORCEPROP 1 LASTPIN (5450 675) $PN 2
J 0
(5460 655);
DISPLAY 0.489362 (5460 655);
FORCEPROP 1 LAST MATERIAL X6S
J 0
(5500 675);
DISPLAY 0.489362 (5500 675);
PAINT SKYBLUE (5500 675);
FORCEPROP 1 LAST TOLERANCE 20%
J 0
(5500 725);
DISPLAY 0.489362 (5500 725);
PAINT SKYBLUE (5500 725);
FORCEPROP 1 LAST VALUE 22UF
J 0
(5500 825);
DISPLAY 0.489362 (5500 825);
PAINT SKYBLUE (5500 825);
FORCEPROP 1 LAST VOLTAGE 4V
J 0
(5500 775);
DISPLAY 0.489362 (5500 775);
PAINT SKYBLUE (5500 775);
FORCEPROP 1 LAST PACK_TYPE C0402
J 0
(5500 575);
DISPLAY 0.489362 (5500 575);
PAINT SKYBLUE (5500 575);
FORCEPROP 2 LAST CDS_LIB pure_quanta
J 0
(5450 775);
PAINT MONO (5450 775);
DISPLAY INVISIBLE (5450 775);
FORCEPROP 1 LAST PATH I84
J 0
(5500 925);
DISPLAY 0.978723 (5500 925);
PAINT WHITE (5500 925);
DISPLAY INVISIBLE (5500 925);
FORCEPROP 1 LAST PART_NUMBER CH622KMEB02
J 0
(5500 625);
DISPLAY 0.489362 (5500 625);
PAINT SKYBLUE (5500 625);
DISPLAY INVISIBLE (5500 625);
FORCEADD Q_CAP..1
(5450 1375);
FORCEPROP 1 LAST LOCATION C2488
J 0
(5500 1475);
DISPLAY 0.489362 (5500 1475);
PAINT SKYBLUE (5500 1475);
FORCEPROP 2 LAST $SEC 1
J 0
(5500 1575);
DISPLAY 0.680851 (5500 1575);
PAINT MONO (5500 1575);
DISPLAY INVISIBLE (5500 1575);
FORCEPROP 2 LAST CDS_SEC 1
J 0
(5500 1575);
DISPLAY 1.021277 (5500 1575);
DISPLAY INVISIBLE (5500 1575);
FORCEPROP 1 LASTPIN (5450 1475) $PN 1
J 0
(5460 1455);
DISPLAY 0.489362 (5460 1455);
FORCEPROP 1 LASTPIN (5450 1275) $PN 2
J 0
(5460 1255);
DISPLAY 0.489362 (5460 1255);
FORCEPROP 1 LAST MATERIAL X6S
J 0
(5500 1275);
DISPLAY 0.489362 (5500 1275);
PAINT SKYBLUE (5500 1275);
FORCEPROP 1 LAST TOLERANCE 20%
J 0
(5500 1325);
DISPLAY 0.489362 (5500 1325);
PAINT SKYBLUE (5500 1325);
FORCEPROP 1 LAST VALUE 22UF
J 0
(5500 1425);
DISPLAY 0.489362 (5500 1425);
PAINT SKYBLUE (5500 1425);
FORCEPROP 1 LAST VOLTAGE 4V
J 0
(5500 1375);
DISPLAY 0.489362 (5500 1375);
PAINT SKYBLUE (5500 1375);
FORCEPROP 1 LAST PACK_TYPE C0402
J 0
(5500 1175);
DISPLAY 0.489362 (5500 1175);
PAINT SKYBLUE (5500 1175);
FORCEPROP 2 LAST CDS_LIB pure_quanta
J 0
(5450 1375);
PAINT MONO (5450 1375);
DISPLAY INVISIBLE (5450 1375);
FORCEPROP 1 LAST PATH I85
J 0
(5500 1525);
DISPLAY 0.978723 (5500 1525);
PAINT WHITE (5500 1525);
DISPLAY INVISIBLE (5500 1525);
FORCEPROP 1 LAST PART_NUMBER CH622KMEB02
J 0
(5500 1225);
DISPLAY 0.489362 (5500 1225);
PAINT SKYBLUE (5500 1225);
DISPLAY INVISIBLE (5500 1225);
FORCEADD Q_CAP..1
(5900 1375);
FORCEPROP 1 LAST LOCATION C2492
J 0
(5950 1475);
DISPLAY 0.489362 (5950 1475);
PAINT SKYBLUE (5950 1475);
FORCEPROP 2 LAST $SEC 1
J 0
(5950 1575);
DISPLAY 0.680851 (5950 1575);
PAINT MONO (5950 1575);
DISPLAY INVISIBLE (5950 1575);
FORCEPROP 2 LAST CDS_SEC 1
J 0
(5950 1575);
DISPLAY 1.021277 (5950 1575);
DISPLAY INVISIBLE (5950 1575);
FORCEPROP 1 LASTPIN (5900 1475) $PN 1
J 0
(5910 1455);
DISPLAY 0.489362 (5910 1455);
FORCEPROP 1 LASTPIN (5900 1275) $PN 2
J 0
(5910 1255);
DISPLAY 0.489362 (5910 1255);
FORCEPROP 1 LAST MATERIAL X6S
J 0
(5950 1275);
DISPLAY 0.489362 (5950 1275);
PAINT SKYBLUE (5950 1275);
FORCEPROP 1 LAST TOLERANCE 20%
J 0
(5950 1325);
DISPLAY 0.489362 (5950 1325);
PAINT SKYBLUE (5950 1325);
FORCEPROP 1 LAST VALUE 22UF
J 0
(5950 1425);
DISPLAY 0.489362 (5950 1425);
PAINT SKYBLUE (5950 1425);
FORCEPROP 1 LAST VOLTAGE 4V
J 0
(5950 1375);
DISPLAY 0.489362 (5950 1375);
PAINT SKYBLUE (5950 1375);
FORCEPROP 1 LAST PACK_TYPE C0402
J 0
(5950 1175);
DISPLAY 0.489362 (5950 1175);
PAINT SKYBLUE (5950 1175);
FORCEPROP 2 LAST CDS_LIB pure_quanta
J 0
(5900 1375);
PAINT MONO (5900 1375);
DISPLAY INVISIBLE (5900 1375);
FORCEPROP 1 LAST PATH I86
J 0
(5950 1525);
DISPLAY 0.978723 (5950 1525);
PAINT WHITE (5950 1525);
DISPLAY INVISIBLE (5950 1525);
FORCEPROP 1 LAST PART_NUMBER CH622KMEB02
J 0
(5950 1225);
DISPLAY 0.489362 (5950 1225);
PAINT SKYBLUE (5950 1225);
DISPLAY INVISIBLE (5950 1225);
FORCEADD UNIVERSAL_GND..1
(4400 2100);
FORCEPROP 3 LASTPIN (4400 2150) SIG_NAME GND\g
J 0
(4410 2160);
DISPLAY 0.659574 (4410 2160);
PAINT MONO (4410 2160);
DISPLAY INVISIBLE (4410 2160);
FORCEPROP 2 LAST CDS_LIB pure_quanta_power
J 0
(4400 2100);
PAINT MONO (4400 2100);
DISPLAY INVISIBLE (4400 2100);
FORCEPROP 1 LAST HDL_POWER GND
J 1
(4425 2025);
DISPLAY 0.872340 (4425 2025);
PAINT GREEN (4425 2025);
DISPLAY INVISIBLE (4425 2025);
FORCEPROP 1 LAST PATH I87
J 0
(4475 2100);
DISPLAY 0.872340 (4475 2100);
PAINT AQUA (4475 2100);
DISPLAY INVISIBLE (4475 2100);
FORCEADD Q_CAP..1
(4400 2475);
FORCEPROP 1 LAST LOCATION C2475
J 0
(4450 2575);
DISPLAY 0.489362 (4450 2575);
PAINT SKYBLUE (4450 2575);
FORCEPROP 2 LAST $SEC 1
J 0
(4450 2675);
DISPLAY 0.680851 (4450 2675);
PAINT MONO (4450 2675);
DISPLAY INVISIBLE (4450 2675);
FORCEPROP 2 LAST CDS_SEC 1
J 0
(4450 2675);
DISPLAY 1.021277 (4450 2675);
DISPLAY INVISIBLE (4450 2675);
FORCEPROP 1 LASTPIN (4400 2575) $PN 1
J 0
(4410 2555);
DISPLAY 0.489362 (4410 2555);
FORCEPROP 1 LASTPIN (4400 2375) $PN 2
J 0
(4410 2355);
DISPLAY 0.489362 (4410 2355);
FORCEPROP 1 LAST MATERIAL X6S
J 0
(4450 2375);
DISPLAY 0.489362 (4450 2375);
PAINT SKYBLUE (4450 2375);
FORCEPROP 1 LAST TOLERANCE 20%
J 0
(4450 2425);
DISPLAY 0.489362 (4450 2425);
PAINT SKYBLUE (4450 2425);
FORCEPROP 1 LAST VALUE 22UF
J 0
(4450 2525);
DISPLAY 0.489362 (4450 2525);
PAINT SKYBLUE (4450 2525);
FORCEPROP 1 LAST VOLTAGE 4V
J 0
(4450 2475);
DISPLAY 0.489362 (4450 2475);
PAINT SKYBLUE (4450 2475);
FORCEPROP 1 LAST PACK_TYPE C0402
J 0
(4450 2275);
DISPLAY 0.489362 (4450 2275);
PAINT SKYBLUE (4450 2275);
FORCEPROP 2 LAST CDS_LIB pure_quanta
J 0
(4400 2475);
PAINT MONO (4400 2475);
DISPLAY INVISIBLE (4400 2475);
FORCEPROP 1 LAST PATH I88
J 0
(4450 2625);
DISPLAY 0.978723 (4450 2625);
PAINT WHITE (4450 2625);
DISPLAY INVISIBLE (4450 2625);
FORCEPROP 1 LAST PART_NUMBER CH622KMEB02
J 0
(4450 2325);
DISPLAY 0.489362 (4450 2325);
PAINT SKYBLUE (4450 2325);
DISPLAY INVISIBLE (4450 2325);
FORCEADD UNIVERSAL_GND..1
(4400 2775);
FORCEPROP 3 LASTPIN (4400 2825) SIG_NAME GND\g
J 0
(4410 2835);
DISPLAY 0.659574 (4410 2835);
PAINT MONO (4410 2835);
DISPLAY INVISIBLE (4410 2835);
FORCEPROP 2 LAST CDS_LIB pure_quanta_power
J 0
(4400 2775);
PAINT MONO (4400 2775);
DISPLAY INVISIBLE (4400 2775);
FORCEPROP 1 LAST HDL_POWER GND
J 1
(4425 2700);
DISPLAY 0.872340 (4425 2700);
PAINT GREEN (4425 2700);
DISPLAY INVISIBLE (4425 2700);
FORCEPROP 1 LAST PATH I89
J 0
(4475 2775);
DISPLAY 0.872340 (4475 2775);
PAINT AQUA (4475 2775);
DISPLAY INVISIBLE (4475 2775);
FORCEADD Q_CAP..1
(1750 1800);
FORCEPROP 1 LAST LOCATION C2434
J 0
(1800 1900);
DISPLAY 0.489362 (1800 1900);
PAINT SKYBLUE (1800 1900);
FORCEPROP 2 LAST $SEC 1
J 0
(1800 2000);
DISPLAY 0.680851 (1800 2000);
PAINT MONO (1800 2000);
DISPLAY INVISIBLE (1800 2000);
FORCEPROP 2 LAST CDS_SEC 1
J 0
(1800 2000);
DISPLAY 1.021277 (1800 2000);
DISPLAY INVISIBLE (1800 2000);
FORCEPROP 1 LASTPIN (1750 1900) $PN 1
J 0
(1760 1880);
DISPLAY 0.489362 (1760 1880);
FORCEPROP 1 LASTPIN (1750 1700) $PN 2
J 0
(1760 1680);
DISPLAY 0.489362 (1760 1680);
FORCEPROP 1 LAST MATERIAL X6S
J 0
(1800 1700);
DISPLAY 0.489362 (1800 1700);
PAINT SKYBLUE (1800 1700);
FORCEPROP 1 LAST TOLERANCE 20%
J 0
(1800 1750);
DISPLAY 0.489362 (1800 1750);
PAINT SKYBLUE (1800 1750);
FORCEPROP 1 LAST VALUE 22UF
J 0
(1800 1850);
DISPLAY 0.489362 (1800 1850);
PAINT SKYBLUE (1800 1850);
FORCEPROP 1 LAST VOLTAGE 4V
J 0
(1800 1800);
DISPLAY 0.489362 (1800 1800);
PAINT SKYBLUE (1800 1800);
FORCEPROP 1 LAST PACK_TYPE C0402
J 0
(1800 1600);
DISPLAY 0.489362 (1800 1600);
PAINT SKYBLUE (1800 1600);
FORCEPROP 2 LAST CDS_LIB pure_quanta
J 0
(1750 1800);
PAINT MONO (1750 1800);
DISPLAY INVISIBLE (1750 1800);
FORCEPROP 1 LAST PATH I9
J 0
(1800 1950);
DISPLAY 0.978723 (1800 1950);
PAINT WHITE (1800 1950);
DISPLAY INVISIBLE (1800 1950);
FORCEPROP 1 LAST PART_NUMBER CH622KMEB02
J 0
(1800 1650);
DISPLAY 0.489362 (1800 1650);
PAINT SKYBLUE (1800 1650);
DISPLAY INVISIBLE (1800 1650);
FORCEADD Q_CAP..1
(5000 2025);
FORCEPROP 1 LAST LOCATION C2482
J 0
(5050 2125);
DISPLAY 0.489362 (5050 2125);
PAINT SKYBLUE (5050 2125);
FORCEPROP 2 LAST $SEC 1
J 0
(5050 2225);
DISPLAY 0.680851 (5050 2225);
PAINT MONO (5050 2225);
DISPLAY INVISIBLE (5050 2225);
FORCEPROP 2 LAST CDS_SEC 1
J 0
(5050 2225);
DISPLAY 1.021277 (5050 2225);
DISPLAY INVISIBLE (5050 2225);
FORCEPROP 1 LASTPIN (5000 2125) $PN 1
J 0
(5010 2105);
DISPLAY 0.489362 (5010 2105);
FORCEPROP 1 LASTPIN (5000 1925) $PN 2
J 0
(5010 1905);
DISPLAY 0.489362 (5010 1905);
FORCEPROP 1 LAST MATERIAL X6S
J 0
(5050 1925);
DISPLAY 0.489362 (5050 1925);
PAINT SKYBLUE (5050 1925);
FORCEPROP 1 LAST TOLERANCE 20%
J 0
(5050 1975);
DISPLAY 0.489362 (5050 1975);
PAINT SKYBLUE (5050 1975);
FORCEPROP 1 LAST VALUE 22UF
J 0
(5050 2075);
DISPLAY 0.489362 (5050 2075);
PAINT SKYBLUE (5050 2075);
FORCEPROP 1 LAST VOLTAGE 4V
J 0
(5050 2025);
DISPLAY 0.489362 (5050 2025);
PAINT SKYBLUE (5050 2025);
FORCEPROP 1 LAST PACK_TYPE C0402
J 0
(5050 1825);
DISPLAY 0.489362 (5050 1825);
PAINT SKYBLUE (5050 1825);
FORCEPROP 2 LAST CDS_LIB pure_quanta
J 0
(5000 2025);
PAINT MONO (5000 2025);
DISPLAY INVISIBLE (5000 2025);
FORCEPROP 1 LAST PATH I90
J 0
(5050 2175);
DISPLAY 0.978723 (5050 2175);
PAINT WHITE (5050 2175);
DISPLAY INVISIBLE (5050 2175);
FORCEPROP 1 LAST PART_NUMBER CH622KMEB02
J 0
(5050 1875);
DISPLAY 0.489362 (5050 1875);
PAINT SKYBLUE (5050 1875);
DISPLAY INVISIBLE (5050 1875);
FORCEADD UNIVERSAL_POWER..1
(5000 2300);
FORCEPROP 3 LASTPIN (5000 2250) SIG_NAME PVDD11_S3_P1\g
J 0
(5010 2260);
DISPLAY 0.659574 (5010 2260);
PAINT MONO (5010 2260);
DISPLAY INVISIBLE (5010 2260);
FORCEPROP 1 LAST HDL_POWER PVDD11_S3_P1
J 1
(5000 2350);
DISPLAY 0.489362 (5000 2350);
PAINT GREEN (5000 2350);
FORCEPROP 2 LAST CDS_LIB pure_quanta_power
J 0
(5000 2300);
DISPLAY INVISIBLE (5000 2300);
FORCEPROP 1 LAST PATH I91
J 0
(5050 2325);
DISPLAY 0.872340 (5050 2325);
PAINT AQUA (5050 2325);
DISPLAY INVISIBLE (5050 2325);
FORCEADD Q_CAP..1
(5000 2650);
FORCEPROP 1 LAST LOCATION C2481
J 0
(5050 2750);
DISPLAY 0.489362 (5050 2750);
PAINT SKYBLUE (5050 2750);
FORCEPROP 2 LAST $SEC 1
J 0
(5050 2850);
DISPLAY 0.680851 (5050 2850);
PAINT MONO (5050 2850);
DISPLAY INVISIBLE (5050 2850);
FORCEPROP 2 LAST CDS_SEC 1
J 0
(5050 2850);
DISPLAY 1.021277 (5050 2850);
DISPLAY INVISIBLE (5050 2850);
FORCEPROP 1 LASTPIN (5000 2750) $PN 1
J 0
(5010 2730);
DISPLAY 0.489362 (5010 2730);
FORCEPROP 1 LASTPIN (5000 2550) $PN 2
J 0
(5010 2530);
DISPLAY 0.489362 (5010 2530);
FORCEPROP 1 LAST MATERIAL X6S
J 0
(5050 2550);
DISPLAY 0.489362 (5050 2550);
PAINT SKYBLUE (5050 2550);
FORCEPROP 1 LAST TOLERANCE 20%
J 0
(5050 2600);
DISPLAY 0.489362 (5050 2600);
PAINT SKYBLUE (5050 2600);
FORCEPROP 1 LAST VALUE 22UF
J 0
(5050 2700);
DISPLAY 0.489362 (5050 2700);
PAINT SKYBLUE (5050 2700);
FORCEPROP 1 LAST VOLTAGE 4V
J 0
(5050 2650);
DISPLAY 0.489362 (5050 2650);
PAINT SKYBLUE (5050 2650);
FORCEPROP 1 LAST PACK_TYPE C0402
J 0
(5050 2450);
DISPLAY 0.489362 (5050 2450);
PAINT SKYBLUE (5050 2450);
FORCEPROP 2 LAST CDS_LIB pure_quanta
J 0
(5000 2650);
PAINT MONO (5000 2650);
DISPLAY INVISIBLE (5000 2650);
FORCEPROP 1 LAST PATH I92
J 0
(5050 2800);
DISPLAY 0.978723 (5050 2800);
PAINT WHITE (5050 2800);
DISPLAY INVISIBLE (5050 2800);
FORCEPROP 1 LAST PART_NUMBER CH622KMEB02
J 0
(5050 2500);
DISPLAY 0.489362 (5050 2500);
PAINT SKYBLUE (5050 2500);
DISPLAY INVISIBLE (5050 2500);
FORCEADD UNIVERSAL_POWER..1
(5000 2925);
FORCEPROP 3 LASTPIN (5000 2875) SIG_NAME PVDD11_S3_P1\g
J 0
(5010 2885);
DISPLAY 0.659574 (5010 2885);
PAINT MONO (5010 2885);
DISPLAY INVISIBLE (5010 2885);
FORCEPROP 1 LAST HDL_POWER PVDD11_S3_P1
J 1
(5000 2975);
DISPLAY 0.489362 (5000 2975);
PAINT GREEN (5000 2975);
FORCEPROP 2 LAST CDS_LIB pure_quanta_power
J 0
(5000 2925);
DISPLAY INVISIBLE (5000 2925);
FORCEPROP 1 LAST PATH I93
J 0
(5050 2950);
DISPLAY 0.872340 (5050 2950);
PAINT AQUA (5050 2950);
DISPLAY INVISIBLE (5050 2950);
FORCEADD Q_CAP..1
(4400 3150);
FORCEPROP 1 LAST LOCATION C2474
J 0
(4450 3250);
DISPLAY 0.489362 (4450 3250);
PAINT SKYBLUE (4450 3250);
FORCEPROP 2 LAST $SEC 1
J 0
(4450 3350);
DISPLAY 0.680851 (4450 3350);
PAINT MONO (4450 3350);
DISPLAY INVISIBLE (4450 3350);
FORCEPROP 2 LAST CDS_SEC 1
J 0
(4450 3350);
DISPLAY 1.021277 (4450 3350);
DISPLAY INVISIBLE (4450 3350);
FORCEPROP 1 LASTPIN (4400 3250) $PN 1
J 0
(4410 3230);
DISPLAY 0.489362 (4410 3230);
FORCEPROP 1 LASTPIN (4400 3050) $PN 2
J 0
(4410 3030);
DISPLAY 0.489362 (4410 3030);
FORCEPROP 1 LAST MATERIAL X6S
J 0
(4450 3050);
DISPLAY 0.489362 (4450 3050);
PAINT SKYBLUE (4450 3050);
FORCEPROP 1 LAST TOLERANCE 20%
J 0
(4450 3100);
DISPLAY 0.489362 (4450 3100);
PAINT SKYBLUE (4450 3100);
FORCEPROP 1 LAST VALUE 22UF
J 0
(4450 3200);
DISPLAY 0.489362 (4450 3200);
PAINT SKYBLUE (4450 3200);
FORCEPROP 1 LAST VOLTAGE 4V
J 0
(4450 3150);
DISPLAY 0.489362 (4450 3150);
PAINT SKYBLUE (4450 3150);
FORCEPROP 1 LAST PACK_TYPE C0402
J 0
(4450 2950);
DISPLAY 0.489362 (4450 2950);
PAINT SKYBLUE (4450 2950);
FORCEPROP 2 LAST CDS_LIB pure_quanta
J 0
(4400 3150);
PAINT MONO (4400 3150);
DISPLAY INVISIBLE (4400 3150);
FORCEPROP 1 LAST PATH I94
J 0
(4450 3300);
DISPLAY 0.978723 (4450 3300);
PAINT WHITE (4450 3300);
DISPLAY INVISIBLE (4450 3300);
FORCEPROP 1 LAST PART_NUMBER CH622KMEB02
J 0
(4450 3000);
DISPLAY 0.489362 (4450 3000);
PAINT SKYBLUE (4450 3000);
DISPLAY INVISIBLE (4450 3000);
FORCEADD UNIVERSAL_GND..1
(4400 3475);
FORCEPROP 3 LASTPIN (4400 3525) SIG_NAME GND\g
J 0
(4410 3535);
DISPLAY 0.659574 (4410 3535);
PAINT MONO (4410 3535);
DISPLAY INVISIBLE (4410 3535);
FORCEPROP 2 LAST CDS_LIB pure_quanta_power
J 0
(4400 3475);
PAINT MONO (4400 3475);
DISPLAY INVISIBLE (4400 3475);
FORCEPROP 1 LAST HDL_POWER GND
J 1
(4425 3400);
DISPLAY 0.872340 (4425 3400);
PAINT GREEN (4425 3400);
DISPLAY INVISIBLE (4425 3400);
FORCEPROP 1 LAST PATH I95
J 0
(4475 3475);
DISPLAY 0.872340 (4475 3475);
PAINT AQUA (4475 3475);
DISPLAY INVISIBLE (4475 3475);
FORCEADD Q_CAP..1
(4400 3850);
FORCEPROP 1 LAST LOCATION C2473
J 0
(4450 3950);
DISPLAY 0.489362 (4450 3950);
PAINT SKYBLUE (4450 3950);
FORCEPROP 2 LAST $SEC 1
J 0
(4450 4050);
DISPLAY 0.680851 (4450 4050);
PAINT MONO (4450 4050);
DISPLAY INVISIBLE (4450 4050);
FORCEPROP 2 LAST CDS_SEC 1
J 0
(4450 4050);
DISPLAY 1.021277 (4450 4050);
DISPLAY INVISIBLE (4450 4050);
FORCEPROP 1 LASTPIN (4400 3950) $PN 1
J 0
(4410 3930);
DISPLAY 0.489362 (4410 3930);
FORCEPROP 1 LASTPIN (4400 3750) $PN 2
J 0
(4410 3730);
DISPLAY 0.489362 (4410 3730);
FORCEPROP 1 LAST MATERIAL X6S
J 0
(4450 3750);
DISPLAY 0.489362 (4450 3750);
PAINT SKYBLUE (4450 3750);
FORCEPROP 1 LAST TOLERANCE 20%
J 0
(4450 3800);
DISPLAY 0.489362 (4450 3800);
PAINT SKYBLUE (4450 3800);
FORCEPROP 1 LAST VALUE 22UF
J 0
(4450 3900);
DISPLAY 0.489362 (4450 3900);
PAINT SKYBLUE (4450 3900);
FORCEPROP 1 LAST VOLTAGE 4V
J 0
(4450 3850);
DISPLAY 0.489362 (4450 3850);
PAINT SKYBLUE (4450 3850);
FORCEPROP 1 LAST PACK_TYPE C0402
J 0
(4450 3650);
DISPLAY 0.489362 (4450 3650);
PAINT SKYBLUE (4450 3650);
FORCEPROP 2 LAST CDS_LIB pure_quanta
J 0
(4400 3850);
PAINT MONO (4400 3850);
DISPLAY INVISIBLE (4400 3850);
FORCEPROP 1 LAST PATH I96
J 0
(4450 4000);
DISPLAY 0.978723 (4450 4000);
PAINT WHITE (4450 4000);
DISPLAY INVISIBLE (4450 4000);
FORCEPROP 1 LAST PART_NUMBER CH622KMEB02
J 0
(4450 3700);
DISPLAY 0.489362 (4450 3700);
PAINT SKYBLUE (4450 3700);
DISPLAY INVISIBLE (4450 3700);
FORCEADD Q_CAP..1
(5000 3325);
FORCEPROP 1 LAST LOCATION C2480
J 0
(5050 3425);
DISPLAY 0.489362 (5050 3425);
PAINT SKYBLUE (5050 3425);
FORCEPROP 2 LAST $SEC 1
J 0
(5050 3525);
DISPLAY 0.680851 (5050 3525);
PAINT MONO (5050 3525);
DISPLAY INVISIBLE (5050 3525);
FORCEPROP 2 LAST CDS_SEC 1
J 0
(5050 3525);
DISPLAY 1.021277 (5050 3525);
DISPLAY INVISIBLE (5050 3525);
FORCEPROP 1 LASTPIN (5000 3425) $PN 1
J 0
(5010 3405);
DISPLAY 0.489362 (5010 3405);
FORCEPROP 1 LASTPIN (5000 3225) $PN 2
J 0
(5010 3205);
DISPLAY 0.489362 (5010 3205);
FORCEPROP 1 LAST MATERIAL X6S
J 0
(5050 3225);
DISPLAY 0.489362 (5050 3225);
PAINT SKYBLUE (5050 3225);
FORCEPROP 1 LAST TOLERANCE 20%
J 0
(5050 3275);
DISPLAY 0.489362 (5050 3275);
PAINT SKYBLUE (5050 3275);
FORCEPROP 1 LAST VALUE 22UF
J 0
(5050 3375);
DISPLAY 0.489362 (5050 3375);
PAINT SKYBLUE (5050 3375);
FORCEPROP 1 LAST VOLTAGE 4V
J 0
(5050 3325);
DISPLAY 0.489362 (5050 3325);
PAINT SKYBLUE (5050 3325);
FORCEPROP 1 LAST PACK_TYPE C0402
J 0
(5050 3125);
DISPLAY 0.489362 (5050 3125);
PAINT SKYBLUE (5050 3125);
FORCEPROP 2 LAST CDS_LIB pure_quanta
J 0
(5000 3325);
PAINT MONO (5000 3325);
DISPLAY INVISIBLE (5000 3325);
FORCEPROP 1 LAST PATH I97
J 0
(5050 3475);
DISPLAY 0.978723 (5050 3475);
PAINT WHITE (5050 3475);
DISPLAY INVISIBLE (5050 3475);
FORCEPROP 1 LAST PART_NUMBER CH622KMEB02
J 0
(5050 3175);
DISPLAY 0.489362 (5050 3175);
PAINT SKYBLUE (5050 3175);
DISPLAY INVISIBLE (5050 3175);
FORCEADD UNIVERSAL_POWER..1
(5000 3600);
FORCEPROP 3 LASTPIN (5000 3550) SIG_NAME PVDD11_S3_P1\g
J 0
(5010 3560);
DISPLAY 0.659574 (5010 3560);
PAINT MONO (5010 3560);
DISPLAY INVISIBLE (5010 3560);
FORCEPROP 1 LAST HDL_POWER PVDD11_S3_P1
J 1
(5000 3650);
DISPLAY 0.489362 (5000 3650);
PAINT GREEN (5000 3650);
FORCEPROP 2 LAST CDS_LIB pure_quanta_power
J 0
(5000 3600);
DISPLAY INVISIBLE (5000 3600);
FORCEPROP 1 LAST PATH I98
J 0
(5050 3625);
DISPLAY 0.872340 (5050 3625);
PAINT AQUA (5050 3625);
DISPLAY INVISIBLE (5050 3625);
FORCEADD Q_CAP..1
(5450 2025);
FORCEPROP 1 LAST LOCATION C2487
J 0
(5500 2125);
DISPLAY 0.489362 (5500 2125);
PAINT SKYBLUE (5500 2125);
FORCEPROP 2 LAST $SEC 1
J 0
(5500 2225);
DISPLAY 0.680851 (5500 2225);
PAINT MONO (5500 2225);
DISPLAY INVISIBLE (5500 2225);
FORCEPROP 2 LAST CDS_SEC 1
J 0
(5500 2225);
DISPLAY 1.021277 (5500 2225);
DISPLAY INVISIBLE (5500 2225);
FORCEPROP 1 LASTPIN (5450 2125) $PN 1
J 0
(5460 2105);
DISPLAY 0.489362 (5460 2105);
FORCEPROP 1 LASTPIN (5450 1925) $PN 2
J 0
(5460 1905);
DISPLAY 0.489362 (5460 1905);
FORCEPROP 1 LAST MATERIAL X6S
J 0
(5500 1925);
DISPLAY 0.489362 (5500 1925);
PAINT SKYBLUE (5500 1925);
FORCEPROP 1 LAST TOLERANCE 20%
J 0
(5500 1975);
DISPLAY 0.489362 (5500 1975);
PAINT SKYBLUE (5500 1975);
FORCEPROP 1 LAST VALUE 22UF
J 0
(5500 2075);
DISPLAY 0.489362 (5500 2075);
PAINT SKYBLUE (5500 2075);
FORCEPROP 1 LAST VOLTAGE 4V
J 0
(5500 2025);
DISPLAY 0.489362 (5500 2025);
PAINT SKYBLUE (5500 2025);
FORCEPROP 1 LAST PACK_TYPE C0402
J 0
(5500 1825);
DISPLAY 0.489362 (5500 1825);
PAINT SKYBLUE (5500 1825);
FORCEPROP 2 LAST CDS_LIB pure_quanta
J 0
(5450 2025);
PAINT MONO (5450 2025);
DISPLAY INVISIBLE (5450 2025);
FORCEPROP 1 LAST PATH I99
J 0
(5500 2175);
DISPLAY 0.978723 (5500 2175);
PAINT WHITE (5500 2175);
DISPLAY INVISIBLE (5500 2175);
FORCEPROP 1 LAST PART_NUMBER CH622KMEB02
J 0
(5500 1875);
DISPLAY 0.489362 (5500 1875);
PAINT SKYBLUE (5500 1875);
DISPLAY INVISIBLE (5500 1875);
FORCEADD QUANTA_TITLE_BLOCK_C..1
(9425 200);
FORCEPROP 0 LAST CDS_CON_LAST_MODIFIED Thu Sep 14 16:12:04 2023
J 0
(7540 215);
DISPLAY INVISIBLE (7540 215);
FORCEPROP 1 LAST CUSTOM_TXT_CDS <CON_LAST_MODIFIED>
J 0
(7540 215);
DISPLAY 0.978723 (7540 215);
FORCEPROP 2 LAST CUSTOM_TXT_CDS <XR_PAGE_TITLE>
J 0
(1535 5450);
DISPLAY 0.638298 (1535 5450);
PAINT PINK (1535 5450);
DISPLAY INVISIBLE (1535 5450);
FORCEPROP 1 LAST CUSTOM_TXT_CDS <NAME_2>
J 0
(6250 250);
FORCEPROP 1 LAST CUSTOM_TXT_CDS <NAME_1>
J 0
(6250 375);
FORCEPROP 1 LAST CUSTOM_TXT_CDS <Q_NUMBER>
J 0
(8022 303);
DISPLAY 1.212766 (8022 303);
FORCEPROP 1 LAST CUSTOM_TXT_CDS <Q_PROJ>
J 0
(7043 302);
DISPLAY 1.212766 (7043 302);
FORCEPROP 1 LAST CUSTOM_TXT_CDS <Q_REV>
J 0
(9241 303);
DISPLAY 1.212766 (9241 303);
FORCEPROP 1 LAST CUSTOM_TXT_CDS <CON_PAGE_NUM> OF <CON_TOTAL_PAGES>
J 0
(8979 218);
DISPLAY 0.978723 (8979 218);
FORCEPROP 1 LAST Q_TITLE CPU1 CAVITY BOT DECOUPLING CAPS 2/3
J 0
(59 226);
DISPLAY 2.446809 (59 226);
PAINT GREEN (59 226);
FORCEPROP 2 LAST PAGE_BORDER TRUE
J 0
(1535 5450);
DISPLAY 0.638298 (1535 5450);
PAINT PINK (1535 5450);
DISPLAY INVISIBLE (1535 5450);
FORCEPROP 2 LAST CDS_LIB pure_quanta
J 0
(9425 200);
DISPLAY INVISIBLE (9425 200);
FORCEPROP 1 LAST CDS_LMAN_SYM_OUTLINE -9475,6775,100,-125
J 0
(9425 200);
DISPLAY 0.468085 (9425 200);
PAINT GREEN (9425 200);
DISPLAY INVISIBLE (9425 200);
FORCEPROP 2 LAST CDS_XR_PAGE_TITLE CR-74 : @T6G_MB_LIB.T6G(SCH_1):PAGE74
J 0
(1535 5450);
DISPLAY 0.638298 (1535 5450);
PAINT PINK (1535 5450);
DISPLAY INVISIBLE (1535 5450);
FORCEPROP 1 LAST Q_DEPT BU9
J 1
(5662 249);
DISPLAY 1.957447 (5662 249);
PAINT GREEN (5662 249);
DISPLAY INVISIBLE (5662 249);
FORCEPROP 1 LAST COMMENT_BODY TRUE
J 0
(9437 187);
DISPLAY 0.978723 (9437 187);
PAINT GREEN (9437 187);
DISPLAY INVISIBLE (9437 187);
WIRE 16 -1 (1300 850)(850 850);
WIRE 16 -1 (1750 850)(1300 850);
WIRE 16 -1 (1300 850)(1300 975);
WIRE 16 -1 (850 850)(850 975);
WIRE 16 -1 (850 850)(400 850);
WIRE 16 -1 (400 850)(400 975);
WIRE 16 -1 (2200 850)(1750 850);
WIRE 16 -1 (1750 850)(1750 975);
WIRE 16 -1 (2650 850)(2200 850);
WIRE 16 -1 (2200 850)(2200 975);
WIRE 16 -1 (3100 850)(2650 850);
WIRE 16 -1 (2650 850)(2650 975);
WIRE 16 -1 (3100 850)(3100 975);
WIRE 16 -1 (3100 750)(3100 850);
WIRE 16 -1 (1750 1975)(1300 1975);
WIRE 16 -1 (2200 1975)(1750 1975);
WIRE 16 -1 (1750 1900)(1750 1975);
WIRE 16 -1 (1300 1975)(1300 1900);
WIRE 16 -1 (1300 1975)(850 1975);
WIRE 16 -1 (850 1900)(850 1975);
WIRE 16 -1 (850 1975)(400 1975);
WIRE 16 -1 (2650 1975)(2200 1975);
WIRE 16 -1 (2200 1900)(2200 1975);
WIRE 16 -1 (3100 1975)(2650 1975);
WIRE 16 -1 (2650 1975)(2650 1900);
WIRE 16 -1 (400 1975)(400 2025);
WIRE 16 -1 (400 1975)(400 1900);
WIRE 16 -1 (3550 1975)(3100 1975);
WIRE 16 -1 (3100 1900)(3100 1975);
WIRE 16 -1 (4000 1975)(3550 1975);
WIRE 16 -1 (3550 1900)(3550 1975);
WIRE 16 -1 (4400 1975)(4000 1975);
WIRE 16 -1 (4000 1975)(4000 1900);
WIRE 16 -1 (4400 1900)(4400 1975);
WIRE 16 -1 (1300 1575)(850 1575);
WIRE 16 -1 (1750 1575)(1300 1575);
WIRE 16 -1 (1300 1575)(1300 1700);
WIRE 16 -1 (850 1575)(850 1700);
WIRE 16 -1 (850 1575)(400 1575);
WIRE 16 -1 (400 1575)(400 1700);
WIRE 16 -1 (2200 1575)(1750 1575);
WIRE 16 -1 (1750 1575)(1750 1700);
WIRE 16 -1 (2650 1575)(2200 1575);
WIRE 16 -1 (2200 1575)(2200 1700);
WIRE 16 -1 (3100 1575)(2650 1575);
WIRE 16 -1 (2650 1575)(2650 1700);
WIRE 16 -1 (3550 1575)(3100 1575);
WIRE 16 -1 (3100 1575)(3100 1700);
WIRE 16 -1 (4000 1575)(3550 1575);
WIRE 16 -1 (3550 1575)(3550 1700);
WIRE 16 -1 (4400 1575)(4000 1575);
WIRE 16 -1 (4000 1575)(4000 1700);
WIRE 16 -1 (4400 1575)(4400 1700);
WIRE 16 -1 (4400 1475)(4400 1575);
WIRE 16 -1 (1750 1250)(1300 1250);
WIRE 16 -1 (2200 1250)(1750 1250);
WIRE 16 -1 (1750 1175)(1750 1250);
WIRE 16 -1 (1300 1250)(1300 1175);
WIRE 16 -1 (1300 1250)(850 1250);
WIRE 16 -1 (850 1175)(850 1250);
WIRE 16 -1 (850 1250)(400 1250);
WIRE 16 -1 (2650 1250)(2200 1250);
WIRE 16 -1 (2200 1175)(2200 1250);
WIRE 16 -1 (3100 1250)(2650 1250);
WIRE 16 -1 (2650 1250)(2650 1175);
WIRE 16 -1 (400 1250)(400 1300);
WIRE 16 -1 (400 1250)(400 1175);
WIRE 16 -1 (3100 1175)(3100 1250);
WIRE 16 -1 (1300 2925)(850 2925);
WIRE 16 -1 (1750 2925)(1300 2925);
WIRE 16 -1 (1300 2925)(1300 3050);
WIRE 16 -1 (850 2925)(850 3050);
WIRE 16 -1 (850 2925)(400 2925);
WIRE 16 -1 (400 2925)(400 3050);
WIRE 16 -1 (2200 2925)(1750 2925);
WIRE 16 -1 (1750 2925)(1750 3050);
WIRE 16 -1 (2650 2925)(2200 2925);
WIRE 16 -1 (2200 2925)(2200 3050);
WIRE 16 -1 (3100 2925)(2650 2925);
WIRE 16 -1 (2650 2925)(2650 3050);
WIRE 16 -1 (3550 2925)(3100 2925);
WIRE 16 -1 (3100 2925)(3100 3050);
WIRE 16 -1 (4000 2925)(3550 2925);
WIRE 16 -1 (3550 2925)(3550 3050);
WIRE 16 -1 (4400 2925)(4000 2925);
WIRE 16 -1 (4000 2925)(4000 3050);
WIRE 16 -1 (4400 2925)(4400 3050);
WIRE 16 -1 (4400 2825)(4400 2925);
WIRE 16 -1 (1750 2650)(1300 2650);
WIRE 16 -1 (2200 2650)(1750 2650);
WIRE 16 -1 (1750 2575)(1750 2650);
WIRE 16 -1 (1300 2650)(1300 2575);
WIRE 16 -1 (1300 2650)(850 2650);
WIRE 16 -1 (850 2575)(850 2650);
WIRE 16 -1 (850 2650)(400 2650);
WIRE 16 -1 (2650 2650)(2200 2650);
WIRE 16 -1 (2200 2575)(2200 2650);
WIRE 16 -1 (3100 2650)(2650 2650);
WIRE 16 -1 (2650 2650)(2650 2575);
WIRE 16 -1 (400 2650)(400 2700);
WIRE 16 -1 (400 2650)(400 2575);
WIRE 16 -1 (3550 2650)(3100 2650);
WIRE 16 -1 (3100 2575)(3100 2650);
WIRE 16 -1 (4000 2650)(3550 2650);
WIRE 16 -1 (3550 2575)(3550 2650);
WIRE 16 -1 (4400 2650)(4000 2650);
WIRE 16 -1 (4000 2650)(4000 2575);
WIRE 16 -1 (4400 2575)(4400 2650);
WIRE 16 -1 (1300 2250)(850 2250);
WIRE 16 -1 (1750 2250)(1300 2250);
WIRE 16 -1 (1300 2250)(1300 2375);
WIRE 16 -1 (850 2250)(850 2375);
WIRE 16 -1 (850 2250)(400 2250);
WIRE 16 -1 (400 2250)(400 2375);
WIRE 16 -1 (2200 2250)(1750 2250);
WIRE 16 -1 (1750 2250)(1750 2375);
WIRE 16 -1 (2650 2250)(2200 2250);
WIRE 16 -1 (2200 2250)(2200 2375);
WIRE 16 -1 (3100 2250)(2650 2250);
WIRE 16 -1 (2650 2250)(2650 2375);
WIRE 16 -1 (3550 2250)(3100 2250);
WIRE 16 -1 (3100 2250)(3100 2375);
WIRE 16 -1 (4000 2250)(3550 2250);
WIRE 16 -1 (3550 2250)(3550 2375);
WIRE 16 -1 (4400 2250)(4000 2250);
WIRE 16 -1 (4000 2250)(4000 2375);
WIRE 16 -1 (4400 2250)(4400 2375);
WIRE 16 -1 (4400 2150)(4400 2250);
WIRE 16 -1 (1750 4025)(1300 4025);
WIRE 16 -1 (2200 4025)(1750 4025);
WIRE 16 -1 (1750 3950)(1750 4025);
WIRE 16 -1 (1300 4025)(1300 3950);
WIRE 16 -1 (1300 4025)(850 4025);
WIRE 16 -1 (850 3950)(850 4025);
WIRE 16 -1 (850 4025)(400 4025);
WIRE 16 -1 (2650 4025)(2200 4025);
WIRE 16 -1 (2200 3950)(2200 4025);
WIRE 16 -1 (3100 4025)(2650 4025);
WIRE 16 -1 (2650 4025)(2650 3950);
WIRE 16 -1 (400 4025)(400 4075);
WIRE 16 -1 (400 4025)(400 3950);
WIRE 16 -1 (3550 4025)(3100 4025);
WIRE 16 -1 (3100 3950)(3100 4025);
WIRE 16 -1 (4000 4025)(3550 4025);
WIRE 16 -1 (3550 3950)(3550 4025);
WIRE 16 -1 (4400 4025)(4000 4025);
WIRE 16 -1 (4000 4025)(4000 3950);
WIRE 16 -1 (4400 3950)(4400 4025);
WIRE 16 -1 (1300 3625)(850 3625);
WIRE 16 -1 (1750 3625)(1300 3625);
WIRE 16 -1 (1300 3625)(1300 3750);
WIRE 16 -1 (850 3625)(850 3750);
WIRE 16 -1 (850 3625)(400 3625);
WIRE 16 -1 (400 3625)(400 3750);
WIRE 16 -1 (2200 3625)(1750 3625);
WIRE 16 -1 (1750 3625)(1750 3750);
WIRE 16 -1 (2650 3625)(2200 3625);
WIRE 16 -1 (2200 3625)(2200 3750);
WIRE 16 -1 (3100 3625)(2650 3625);
WIRE 16 -1 (2650 3625)(2650 3750);
WIRE 16 -1 (3550 3625)(3100 3625);
WIRE 16 -1 (3100 3625)(3100 3750);
WIRE 16 -1 (4000 3625)(3550 3625);
WIRE 16 -1 (3550 3625)(3550 3750);
WIRE 16 -1 (4400 3625)(4000 3625);
WIRE 16 -1 (4000 3625)(4000 3750);
WIRE 16 -1 (4400 3625)(4400 3750);
WIRE 16 -1 (4400 3525)(4400 3625);
WIRE 16 -1 (1750 3325)(1300 3325);
WIRE 16 -1 (2200 3325)(1750 3325);
WIRE 16 -1 (1750 3250)(1750 3325);
WIRE 16 -1 (1300 3325)(1300 3250);
WIRE 16 -1 (1300 3325)(850 3325);
WIRE 16 -1 (850 3250)(850 3325);
WIRE 16 -1 (850 3325)(400 3325);
WIRE 16 -1 (2650 3325)(2200 3325);
WIRE 16 -1 (2200 3250)(2200 3325);
WIRE 16 -1 (3100 3325)(2650 3325);
WIRE 16 -1 (2650 3325)(2650 3250);
WIRE 16 -1 (400 3325)(400 3375);
WIRE 16 -1 (400 3325)(400 3250);
WIRE 16 -1 (3550 3325)(3100 3325);
WIRE 16 -1 (3100 3250)(3100 3325);
WIRE 16 -1 (4000 3325)(3550 3325);
WIRE 16 -1 (3550 3250)(3550 3325);
WIRE 16 -1 (4400 3325)(4000 3325);
WIRE 16 -1 (4000 3325)(4000 3250);
WIRE 16 -1 (4400 3250)(4400 3325);
WIRE 16 -1 (1750 4725)(1300 4725);
WIRE 16 -1 (2200 4725)(1750 4725);
WIRE 16 -1 (1750 4650)(1750 4725);
WIRE 16 -1 (1300 4725)(1300 4650);
WIRE 16 -1 (1300 4725)(850 4725);
WIRE 16 -1 (850 4650)(850 4725);
WIRE 16 -1 (850 4725)(400 4725);
WIRE 16 -1 (2650 4725)(2200 4725);
WIRE 16 -1 (2200 4650)(2200 4725);
WIRE 16 -1 (3100 4725)(2650 4725);
WIRE 16 -1 (2650 4725)(2650 4650);
WIRE 16 -1 (400 4725)(400 4775);
WIRE 16 -1 (400 4725)(400 4650);
WIRE 16 -1 (3550 4725)(3100 4725);
WIRE 16 -1 (3100 4650)(3100 4725);
WIRE 16 -1 (4000 4725)(3550 4725);
WIRE 16 -1 (3550 4650)(3550 4725);
WIRE 16 -1 (4400 4725)(4000 4725);
WIRE 16 -1 (4000 4725)(4000 4650);
WIRE 16 -1 (4400 4650)(4400 4725);
WIRE 16 -1 (1300 4325)(850 4325);
WIRE 16 -1 (1750 4325)(1300 4325);
WIRE 16 -1 (1300 4325)(1300 4450);
WIRE 16 -1 (850 4325)(850 4450);
WIRE 16 -1 (850 4325)(400 4325);
WIRE 16 -1 (400 4325)(400 4450);
WIRE 16 -1 (2200 4325)(1750 4325);
WIRE 16 -1 (1750 4325)(1750 4450);
WIRE 16 -1 (2650 4325)(2200 4325);
WIRE 16 -1 (2200 4325)(2200 4450);
WIRE 16 -1 (3100 4325)(2650 4325);
WIRE 16 -1 (2650 4325)(2650 4450);
WIRE 16 -1 (3550 4325)(3100 4325);
WIRE 16 -1 (3100 4325)(3100 4450);
WIRE 16 -1 (4000 4325)(3550 4325);
WIRE 16 -1 (3550 4325)(3550 4450);
WIRE 16 -1 (4400 4325)(4000 4325);
WIRE 16 -1 (4000 4325)(4000 4450);
WIRE 16 -1 (4400 4325)(4400 4450);
WIRE 16 -1 (4400 4225)(4400 4325);
WIRE 16 -1 (4400 5000)(4400 5125);
WIRE 16 -1 (4400 4900)(4400 5000);
WIRE 16 -1 (4400 5000)(4000 5000);
WIRE 16 -1 (4000 5000)(4000 5125);
WIRE 16 -1 (4000 5000)(3550 5000);
WIRE 16 -1 (3550 5000)(3550 5125);
WIRE 16 -1 (3550 5000)(3100 5000);
WIRE 16 -1 (3100 5000)(3100 5125);
WIRE 16 -1 (3100 5000)(2650 5000);
WIRE 16 -1 (2650 5000)(2650 5125);
WIRE 16 -1 (2650 5000)(2200 5000);
WIRE 16 -1 (2200 5000)(2200 5125);
WIRE 16 -1 (2200 5000)(1750 5000);
WIRE 16 -1 (1750 5000)(1750 5125);
WIRE 16 -1 (1750 5000)(1300 5000);
WIRE 16 -1 (1300 5000)(1300 5125);
WIRE 16 -1 (1300 5000)(850 5000);
WIRE 16 -1 (850 5000)(850 5125);
WIRE 16 -1 (850 5000)(400 5000);
WIRE 16 -1 (400 5000)(400 5125);
WIRE 16 -1 (1750 6050)(1300 6050);
WIRE 16 -1 (2200 6050)(1750 6050);
WIRE 16 -1 (1750 5975)(1750 6050);
WIRE 16 -1 (1300 6050)(1300 5975);
WIRE 16 -1 (1300 6050)(850 6050);
WIRE 16 -1 (850 5975)(850 6050);
WIRE 16 -1 (850 6050)(400 6050);
WIRE 16 -1 (2650 6050)(2200 6050);
WIRE 16 -1 (2200 5975)(2200 6050);
WIRE 16 -1 (3100 6050)(2650 6050);
WIRE 16 -1 (2650 6050)(2650 5975);
WIRE 16 -1 (400 6050)(400 6100);
WIRE 16 -1 (400 6050)(400 5975);
WIRE 16 -1 (3550 6050)(3100 6050);
WIRE 16 -1 (3100 5975)(3100 6050);
WIRE 16 -1 (4000 6050)(3550 6050);
WIRE 16 -1 (3550 5975)(3550 6050);
WIRE 16 -1 (4400 6050)(4000 6050);
WIRE 16 -1 (4000 6050)(4000 5975);
WIRE 16 -1 (4400 5975)(4400 6050);
WIRE 16 -1 (1300 5650)(850 5650);
WIRE 16 -1 (1750 5650)(1300 5650);
WIRE 16 -1 (1300 5650)(1300 5775);
WIRE 16 -1 (850 5650)(850 5775);
WIRE 16 -1 (850 5650)(400 5650);
WIRE 16 -1 (400 5650)(400 5775);
WIRE 16 -1 (2200 5650)(1750 5650);
WIRE 16 -1 (1750 5650)(1750 5775);
WIRE 16 -1 (2650 5650)(2200 5650);
WIRE 16 -1 (2200 5650)(2200 5775);
WIRE 16 -1 (3100 5650)(2650 5650);
WIRE 16 -1 (2650 5650)(2650 5775);
WIRE 16 -1 (3550 5650)(3100 5650);
WIRE 16 -1 (3100 5650)(3100 5775);
WIRE 16 -1 (4000 5650)(3550 5650);
WIRE 16 -1 (3550 5650)(3550 5775);
WIRE 16 -1 (4400 5650)(4000 5650);
WIRE 16 -1 (4000 5650)(4000 5775);
WIRE 16 -1 (4400 5650)(4400 5775);
WIRE 16 -1 (4400 5550)(4400 5650);
WIRE 16 -1 (1750 5400)(1300 5400);
WIRE 16 -1 (2200 5400)(1750 5400);
WIRE 16 -1 (1750 5325)(1750 5400);
WIRE 16 -1 (1300 5400)(1300 5325);
WIRE 16 -1 (1300 5400)(850 5400);
WIRE 16 -1 (850 5325)(850 5400);
WIRE 16 -1 (850 5400)(400 5400);
WIRE 16 -1 (2650 5400)(2200 5400);
WIRE 16 -1 (2200 5325)(2200 5400);
WIRE 16 -1 (3100 5400)(2650 5400);
WIRE 16 -1 (2650 5400)(2650 5325);
WIRE 16 -1 (400 5400)(400 5450);
WIRE 16 -1 (400 5400)(400 5325);
WIRE 16 -1 (3550 5400)(3100 5400);
WIRE 16 -1 (3100 5325)(3100 5400);
WIRE 16 -1 (4000 5400)(3550 5400);
WIRE 16 -1 (3550 5325)(3550 5400);
WIRE 16 -1 (4400 5400)(4000 5400);
WIRE 16 -1 (4000 5400)(4000 5325);
WIRE 16 -1 (4400 5325)(4400 5400);
WIRE 16 3135 (225 6475)(4725 6475);
WIRE 16 3135 (225 600)(225 6475);
WIRE 16 3135 (4725 600)(4725 6475);
WIRE 16 3135 (225 600)(4725 600);
WIRE 16 -1 (5900 1800)(5450 1800);
WIRE 16 -1 (6350 1800)(5900 1800);
WIRE 16 -1 (5900 1800)(5900 1925);
WIRE 16 -1 (5450 1800)(5450 1925);
WIRE 16 -1 (5450 1800)(5000 1800);
WIRE 16 -1 (5000 1800)(5000 1925);
WIRE 16 -1 (6800 1800)(6350 1800);
WIRE 16 -1 (6350 1800)(6350 1925);
WIRE 16 -1 (7250 1800)(6800 1800);
WIRE 16 -1 (6800 1800)(6800 1925);
WIRE 16 -1 (7700 1800)(7250 1800);
WIRE 16 -1 (7250 1800)(7250 1925);
WIRE 16 -1 (8150 1800)(7700 1800);
WIRE 16 -1 (7700 1800)(7700 1925);
WIRE 16 -1 (8600 1800)(8150 1800);
WIRE 16 -1 (8150 1800)(8150 1925);
WIRE 16 -1 (9000 1800)(8600 1800);
WIRE 16 -1 (8600 1800)(8600 1925);
WIRE 16 -1 (9000 1800)(9000 1925);
WIRE 16 -1 (9000 1700)(9000 1800);
WIRE 16 -1 (6350 1550)(5900 1550);
WIRE 16 -1 (6800 1550)(6350 1550);
WIRE 16 -1 (6350 1475)(6350 1550);
WIRE 16 -1 (5900 1550)(5900 1475);
WIRE 16 -1 (5900 1550)(5450 1550);
WIRE 16 -1 (5450 1475)(5450 1550);
WIRE 16 -1 (5450 1550)(5000 1550);
WIRE 16 -1 (7250 1550)(6800 1550);
WIRE 16 -1 (6800 1475)(6800 1550);
WIRE 16 -1 (7700 1550)(7250 1550);
WIRE 16 -1 (7250 1550)(7250 1475);
WIRE 16 -1 (5000 1550)(5000 1600);
WIRE 16 -1 (5000 1550)(5000 1475);
WIRE 16 -1 (8150 1550)(7700 1550);
WIRE 16 -1 (7700 1475)(7700 1550);
WIRE 16 -1 (8600 1550)(8150 1550);
WIRE 16 -1 (8150 1475)(8150 1550);
WIRE 16 -1 (9000 1550)(8600 1550);
WIRE 16 -1 (8600 1550)(8600 1475);
WIRE 16 -1 (9000 1475)(9000 1550);
WIRE 16 -1 (5900 1150)(5450 1150);
WIRE 16 -1 (6350 1150)(5900 1150);
WIRE 16 -1 (5900 1150)(5900 1275);
WIRE 16 -1 (5450 1150)(5450 1275);
WIRE 16 -1 (5450 1150)(5000 1150);
WIRE 16 -1 (5000 1150)(5000 1275);
WIRE 16 -1 (6800 1150)(6350 1150);
WIRE 16 -1 (6350 1150)(6350 1275);
WIRE 16 -1 (7250 1150)(6800 1150);
WIRE 16 -1 (6800 1150)(6800 1275);
WIRE 16 -1 (7700 1150)(7250 1150);
WIRE 16 -1 (7250 1150)(7250 1275);
WIRE 16 -1 (8150 1150)(7700 1150);
WIRE 16 -1 (7700 1150)(7700 1275);
WIRE 16 -1 (8600 1150)(8150 1150);
WIRE 16 -1 (8150 1275)(8150 1150);
WIRE 16 -1 (9000 1150)(8600 1150);
WIRE 16 -1 (8600 1150)(8600 1275);
WIRE 16 -1 (9000 1150)(9000 1275);
WIRE 16 -1 (9000 1050)(9000 1150);
WIRE 16 -1 (5450 875)(5450 950);
WIRE 16 -1 (5450 950)(5000 950);
WIRE 16 -1 (5000 950)(5000 1000);
WIRE 16 -1 (5000 950)(5000 875);
WIRE 16 -1 (5450 550)(5450 675);
WIRE 16 -1 (5450 500)(5450 550);
WIRE 16 -1 (5450 550)(5000 550);
WIRE 16 -1 (5000 550)(5000 675);
WIRE 16 -1 (6350 3500)(5900 3500);
WIRE 16 -1 (6800 3500)(6350 3500);
WIRE 16 -1 (6350 3425)(6350 3500);
WIRE 16 -1 (5900 3500)(5900 3425);
WIRE 16 -1 (5900 3500)(5450 3500);
WIRE 16 -1 (5450 3425)(5450 3500);
WIRE 16 -1 (5450 3500)(5000 3500);
WIRE 16 -1 (7250 3500)(6800 3500);
WIRE 16 -1 (6800 3425)(6800 3500);
WIRE 16 -1 (7700 3500)(7250 3500);
WIRE 16 -1 (7250 3500)(7250 3425);
WIRE 16 -1 (5000 3500)(5000 3425);
WIRE 16 -1 (5000 3500)(5000 3550);
WIRE 16 -1 (8150 3500)(7700 3500);
WIRE 16 -1 (7700 3425)(7700 3500);
WIRE 16 -1 (8600 3500)(8150 3500);
WIRE 16 -1 (8150 3425)(8150 3500);
WIRE 16 -1 (9000 3500)(8600 3500);
WIRE 16 -1 (8600 3500)(8600 3425);
WIRE 16 -1 (9000 3425)(9000 3500);
WIRE 16 -1 (5900 3100)(5450 3100);
WIRE 16 -1 (6350 3100)(5900 3100);
WIRE 16 -1 (5900 3100)(5900 3225);
WIRE 16 -1 (5450 3100)(5450 3225);
WIRE 16 -1 (5450 3100)(5000 3100);
WIRE 16 -1 (5000 3100)(5000 3225);
WIRE 16 -1 (6800 3100)(6350 3100);
WIRE 16 -1 (6350 3100)(6350 3225);
WIRE 16 -1 (7250 3100)(6800 3100);
WIRE 16 -1 (6800 3100)(6800 3225);
WIRE 16 -1 (7700 3100)(7250 3100);
WIRE 16 -1 (7250 3100)(7250 3225);
WIRE 16 -1 (8150 3100)(7700 3100);
WIRE 16 -1 (7700 3100)(7700 3225);
WIRE 16 -1 (8600 3100)(8150 3100);
WIRE 16 -1 (8150 3100)(8150 3225);
WIRE 16 -1 (9000 3100)(8600 3100);
WIRE 16 -1 (8600 3100)(8600 3225);
WIRE 16 -1 (9000 3100)(9000 3225);
WIRE 16 -1 (9000 3000)(9000 3100);
WIRE 16 -1 (6350 2825)(5900 2825);
WIRE 16 -1 (6800 2825)(6350 2825);
WIRE 16 -1 (6350 2750)(6350 2825);
WIRE 16 -1 (5900 2825)(5900 2750);
WIRE 16 -1 (5900 2825)(5450 2825);
WIRE 16 -1 (5450 2750)(5450 2825);
WIRE 16 -1 (5450 2825)(5000 2825);
WIRE 16 -1 (7250 2825)(6800 2825);
WIRE 16 -1 (6800 2750)(6800 2825);
WIRE 16 -1 (7700 2825)(7250 2825);
WIRE 16 -1 (7250 2825)(7250 2750);
WIRE 16 -1 (5000 2825)(5000 2875);
WIRE 16 -1 (5000 2825)(5000 2750);
WIRE 16 -1 (8150 2825)(7700 2825);
WIRE 16 -1 (7700 2750)(7700 2825);
WIRE 16 -1 (8600 2825)(8150 2825);
WIRE 16 -1 (8150 2750)(8150 2825);
WIRE 16 -1 (9000 2825)(8600 2825);
WIRE 16 -1 (8600 2825)(8600 2750);
WIRE 16 -1 (9000 2750)(9000 2825);
WIRE 16 -1 (5900 2425)(5450 2425);
WIRE 16 -1 (6350 2425)(5900 2425);
WIRE 16 -1 (5900 2425)(5900 2550);
WIRE 16 -1 (5450 2425)(5450 2550);
WIRE 16 -1 (5450 2425)(5000 2425);
WIRE 16 -1 (5000 2425)(5000 2550);
WIRE 16 -1 (6800 2425)(6350 2425);
WIRE 16 -1 (6350 2425)(6350 2550);
WIRE 16 -1 (7250 2425)(6800 2425);
WIRE 16 -1 (6800 2425)(6800 2550);
WIRE 16 -1 (7700 2425)(7250 2425);
WIRE 16 -1 (7250 2425)(7250 2550);
WIRE 16 -1 (8150 2425)(7700 2425);
WIRE 16 -1 (7700 2425)(7700 2550);
WIRE 16 -1 (8600 2425)(8150 2425);
WIRE 16 -1 (8150 2425)(8150 2550);
WIRE 16 -1 (9000 2425)(8600 2425);
WIRE 16 -1 (8600 2425)(8600 2550);
WIRE 16 -1 (9000 2425)(9000 2550);
WIRE 16 -1 (9000 2350)(9000 2425);
WIRE 16 -1 (6350 2200)(5900 2200);
WIRE 16 -1 (6800 2200)(6350 2200);
WIRE 16 -1 (6350 2125)(6350 2200);
WIRE 16 -1 (5900 2200)(5900 2125);
WIRE 16 -1 (5900 2200)(5450 2200);
WIRE 16 -1 (5450 2125)(5450 2200);
WIRE 16 -1 (5450 2200)(5000 2200);
WIRE 16 -1 (7250 2200)(6800 2200);
WIRE 16 -1 (6800 2125)(6800 2200);
WIRE 16 -1 (7700 2200)(7250 2200);
WIRE 16 -1 (7250 2200)(7250 2125);
WIRE 16 -1 (5000 2200)(5000 2125);
WIRE 16 -1 (5000 2200)(5000 2250);
WIRE 16 -1 (8150 2200)(7700 2200);
WIRE 16 -1 (7700 2125)(7700 2200);
WIRE 16 -1 (8600 2200)(8150 2200);
WIRE 16 -1 (8150 2125)(8150 2200);
WIRE 16 -1 (9000 2200)(8600 2200);
WIRE 16 -1 (8600 2200)(8600 2125);
WIRE 16 -1 (9000 2125)(9000 2200);
WIRE 16 -1 (5000 4075)(5000 4200);
WIRE 16 -1 (5450 4075)(5000 4075);
WIRE 16 -1 (5450 4075)(5450 4200);
WIRE 16 -1 (5900 4075)(5450 4075);
WIRE 16 -1 (5900 4075)(5900 4200);
WIRE 16 -1 (6350 4075)(5900 4075);
WIRE 16 -1 (6350 4075)(6350 4200);
WIRE 16 -1 (6350 3975)(6350 4075);
WIRE 16 -1 (6325 6050)(5875 6050);
WIRE 16 -1 (6775 6050)(6325 6050);
WIRE 16 -1 (6325 5975)(6325 6050);
WIRE 16 -1 (5875 6050)(5875 5975);
WIRE 16 -1 (5875 6050)(5425 6050);
WIRE 16 -1 (5425 5975)(5425 6050);
WIRE 16 -1 (5425 6050)(4975 6050);
WIRE 16 -1 (7225 6050)(6775 6050);
WIRE 16 -1 (6775 5975)(6775 6050);
WIRE 16 -1 (7675 6050)(7225 6050);
WIRE 16 -1 (7225 6050)(7225 5975);
WIRE 16 -1 (4975 6050)(4975 5975);
WIRE 16 -1 (4975 6050)(4975 6100);
WIRE 16 -1 (8125 6050)(7675 6050);
WIRE 16 -1 (7675 5975)(7675 6050);
WIRE 16 -1 (8575 6050)(8125 6050);
WIRE 16 -1 (8125 5975)(8125 6050);
WIRE 16 -1 (8975 6050)(8575 6050);
WIRE 16 -1 (8575 6050)(8575 5975);
WIRE 16 -1 (8975 5975)(8975 6050);
WIRE 16 -1 (5875 5650)(5425 5650);
WIRE 16 -1 (6325 5650)(5875 5650);
WIRE 16 -1 (5875 5650)(5875 5775);
WIRE 16 -1 (5425 5650)(5425 5775);
WIRE 16 -1 (5425 5650)(4975 5650);
WIRE 16 -1 (4975 5650)(4975 5775);
WIRE 16 -1 (6775 5650)(6325 5650);
WIRE 16 -1 (6325 5650)(6325 5775);
WIRE 16 -1 (7225 5650)(6775 5650);
WIRE 16 -1 (6775 5650)(6775 5775);
WIRE 16 -1 (7675 5650)(7225 5650);
WIRE 16 -1 (7225 5650)(7225 5775);
WIRE 16 -1 (8125 5650)(7675 5650);
WIRE 16 -1 (7675 5650)(7675 5775);
WIRE 16 -1 (8575 5650)(8125 5650);
WIRE 16 -1 (8125 5650)(8125 5775);
WIRE 16 -1 (8975 5650)(8575 5650);
WIRE 16 -1 (8575 5650)(8575 5775);
WIRE 16 -1 (8975 5650)(8975 5775);
WIRE 16 -1 (8975 5550)(8975 5650);
WIRE 16 -1 (6325 5250)(5875 5250);
WIRE 16 -1 (6775 5250)(6325 5250);
WIRE 16 -1 (6325 5175)(6325 5250);
WIRE 16 -1 (5875 5250)(5875 5175);
WIRE 16 -1 (5875 5250)(5425 5250);
WIRE 16 -1 (5425 5175)(5425 5250);
WIRE 16 -1 (5425 5250)(4975 5250);
WIRE 16 -1 (7225 5250)(6775 5250);
WIRE 16 -1 (6775 5175)(6775 5250);
WIRE 16 -1 (7675 5250)(7225 5250);
WIRE 16 -1 (7225 5250)(7225 5175);
WIRE 16 -1 (4975 5250)(4975 5300);
WIRE 16 -1 (4975 5250)(4975 5175);
WIRE 16 -1 (8125 5250)(7675 5250);
WIRE 16 -1 (7675 5175)(7675 5250);
WIRE 16 -1 (8575 5250)(8125 5250);
WIRE 16 -1 (8125 5175)(8125 5250);
WIRE 16 -1 (8975 5250)(8575 5250);
WIRE 16 -1 (8575 5250)(8575 5175);
WIRE 16 -1 (8975 5175)(8975 5250);
WIRE 16 -1 (5875 4850)(5425 4850);
WIRE 16 -1 (6325 4850)(5875 4850);
WIRE 16 -1 (5875 4850)(5875 4975);
WIRE 16 -1 (5425 4850)(5425 4975);
WIRE 16 -1 (5425 4850)(4975 4850);
WIRE 16 -1 (4975 4850)(4975 4975);
WIRE 16 -1 (6775 4850)(6325 4850);
WIRE 16 -1 (6325 4850)(6325 4975);
WIRE 16 -1 (7225 4850)(6775 4850);
WIRE 16 -1 (6775 4850)(6775 4975);
WIRE 16 -1 (7675 4850)(7225 4850);
WIRE 16 -1 (7225 4850)(7225 4975);
WIRE 16 -1 (8125 4850)(7675 4850);
WIRE 16 -1 (7675 4850)(7675 4975);
WIRE 16 -1 (8575 4850)(8125 4850);
WIRE 16 -1 (8125 4850)(8125 4975);
WIRE 16 -1 (8975 4850)(8575 4850);
WIRE 16 -1 (8575 4850)(8575 4975);
WIRE 16 -1 (8975 4850)(8975 4975);
WIRE 16 -1 (8975 4750)(8975 4850);
WIRE 16 -1 (6350 4475)(5900 4475);
WIRE 16 -1 (6350 4400)(6350 4475);
WIRE 16 -1 (5900 4475)(5900 4400);
WIRE 16 -1 (5900 4475)(5450 4475);
WIRE 16 -1 (5450 4400)(5450 4475);
WIRE 16 -1 (5450 4475)(5000 4475);
WIRE 16 -1 (5000 4475)(5000 4525);
WIRE 16 -1 (5000 4475)(5000 4400);
WIRE 16 3135 (4850 6475)(9300 6475);
WIRE 16 3135 (4850 3850)(4850 6475);
WIRE 16 3135 (9300 3850)(9300 6475);
WIRE 16 3135 (4850 3850)(9300 3850);
DOT 1 (850 850);
DOT 1 (400 1250);
DOT 1 (850 1250);
DOT 1 (850 1575);
DOT 1 (1750 850);
DOT 1 (1300 850);
DOT 1 (1300 1250);
DOT 1 (1300 1575);
DOT 1 (1750 1250);
DOT 1 (1750 1575);
DOT 1 (400 1975);
DOT 1 (400 2650);
DOT 1 (850 1975);
DOT 1 (850 2250);
DOT 1 (850 2650);
DOT 1 (850 2925);
DOT 1 (400 3325);
DOT 1 (850 3325);
DOT 1 (850 3625);
DOT 1 (1300 1975);
DOT 1 (1300 2250);
DOT 1 (1300 2650);
DOT 1 (1750 1975);
DOT 1 (1750 2250);
DOT 1 (1750 2650);
DOT 1 (1750 2925);
DOT 1 (1300 2925);
DOT 1 (1300 3325);
DOT 1 (1300 3625);
DOT 1 (1750 3325);
DOT 1 (1750 3625);
DOT 1 (2200 850);
DOT 1 (2650 850);
DOT 1 (2200 1250);
DOT 1 (2200 1575);
DOT 1 (2650 1250);
DOT 1 (2650 1575);
DOT 1 (3100 850);
DOT 1 (3100 1575);
DOT 1 (3550 1575);
DOT 1 (4000 1575);
DOT 1 (2200 1975);
DOT 1 (2200 2250);
DOT 1 (2200 2650);
DOT 1 (2650 1975);
DOT 1 (2650 2250);
DOT 1 (2650 2650);
DOT 1 (2650 2925);
DOT 1 (2200 2925);
DOT 1 (2200 3325);
DOT 1 (2200 3625);
DOT 1 (2650 3325);
DOT 1 (2650 3625);
DOT 1 (3100 1975);
DOT 1 (3100 2250);
DOT 1 (3550 1975);
DOT 1 (3550 2250);
DOT 1 (3100 2650);
DOT 1 (3550 2650);
DOT 1 (4000 1975);
DOT 1 (4000 2250);
DOT 1 (4000 2650);
DOT 1 (4000 2925);
DOT 1 (3550 2925);
DOT 1 (3100 2925);
DOT 1 (3100 3325);
DOT 1 (3550 3325);
DOT 1 (3100 3625);
DOT 1 (3550 3625);
DOT 1 (4000 3325);
DOT 1 (4000 3625);
DOT 1 (400 4025);
DOT 1 (400 4725);
DOT 1 (850 4025);
DOT 1 (850 4325);
DOT 1 (850 4725);
DOT 1 (400 5400);
DOT 1 (850 5000);
DOT 1 (850 5400);
DOT 1 (850 5650);
DOT 1 (1300 4025);
DOT 1 (1300 4325);
DOT 1 (1300 4725);
DOT 1 (1750 4025);
DOT 1 (1750 4325);
DOT 1 (1750 4725);
DOT 1 (1300 5000);
DOT 1 (1300 5400);
DOT 1 (1300 5650);
DOT 1 (1750 5000);
DOT 1 (1750 5400);
DOT 1 (1750 5650);
DOT 1 (1300 6050);
DOT 1 (1750 6050);
DOT 1 (2200 4025);
DOT 1 (2200 4325);
DOT 1 (2200 4725);
DOT 1 (2650 4025);
DOT 1 (2650 4325);
DOT 1 (2650 4725);
DOT 1 (2200 5000);
DOT 1 (2200 5400);
DOT 1 (2200 5650);
DOT 1 (2650 5000);
DOT 1 (2650 5400);
DOT 1 (2650 5650);
DOT 1 (3100 4025);
DOT 1 (3100 4325);
DOT 1 (3550 4025);
DOT 1 (3550 4325);
DOT 1 (3100 4725);
DOT 1 (3550 4725);
DOT 1 (4000 4025);
DOT 1 (4000 4325);
DOT 1 (4000 4725);
DOT 1 (3100 5000);
DOT 1 (3100 5400);
DOT 1 (3550 5000);
DOT 1 (3550 5400);
DOT 1 (3100 5650);
DOT 1 (3550 5650);
DOT 1 (4000 5000);
DOT 1 (4000 5400);
DOT 1 (4000 5650);
DOT 1 (2200 6050);
DOT 1 (2650 6050);
DOT 1 (3100 6050);
DOT 1 (3550 6050);
DOT 1 (4000 6050);
DOT 1 (4400 1575);
DOT 1 (5000 950);
DOT 1 (5000 1550);
DOT 1 (5450 550);
DOT 1 (5450 1150);
DOT 1 (5450 1550);
DOT 1 (5450 1800);
DOT 1 (5900 1150);
DOT 1 (5900 1550);
DOT 1 (5900 1800);
DOT 1 (4400 2250);
DOT 1 (5000 2200);
DOT 1 (5000 2825);
DOT 1 (4400 2925);
DOT 1 (5000 3500);
DOT 1 (5450 2200);
DOT 1 (5450 2425);
DOT 1 (5450 2825);
DOT 1 (5900 2200);
DOT 1 (5900 2825);
DOT 1 (5900 2425);
DOT 1 (5450 3100);
DOT 1 (5450 3500);
DOT 1 (5900 3100);
DOT 1 (5900 3500);
DOT 1 (6350 1150);
DOT 1 (6350 1550);
DOT 1 (6350 1800);
DOT 1 (6800 1150);
DOT 1 (6800 1550);
DOT 1 (6800 1800);
DOT 1 (7250 1150);
DOT 1 (7250 1550);
DOT 1 (7250 1800);
DOT 1 (7700 1150);
DOT 1 (8150 1150);
DOT 1 (7700 1550);
DOT 1 (7700 1800);
DOT 1 (8150 1550);
DOT 1 (8150 1800);
DOT 1 (6350 2200);
DOT 1 (6350 2425);
DOT 1 (6350 2825);
DOT 1 (6800 2200);
DOT 1 (6800 2425);
DOT 1 (6800 2825);
DOT 1 (6350 3100);
DOT 1 (6350 3500);
DOT 1 (6800 3100);
DOT 1 (6800 3500);
DOT 1 (7250 2200);
DOT 1 (7250 2425);
DOT 1 (7250 2825);
DOT 1 (7700 2200);
DOT 1 (8150 2200);
DOT 1 (7700 2425);
DOT 1 (7700 2825);
DOT 1 (8150 2425);
DOT 1 (8150 2825);
DOT 1 (7250 3100);
DOT 1 (7250 3500);
DOT 1 (7700 3100);
DOT 1 (8150 3100);
DOT 1 (7700 3500);
DOT 1 (8150 3500);
DOT 1 (4400 4325);
DOT 1 (5000 4475);
DOT 1 (4400 5000);
DOT 1 (4400 5650);
DOT 1 (4975 5250);
DOT 1 (5450 4075);
DOT 1 (5450 4475);
DOT 1 (5425 4850);
DOT 1 (5900 4075);
DOT 1 (5875 4850);
DOT 1 (5900 4475);
DOT 1 (5425 5250);
DOT 1 (5425 5650);
DOT 1 (5875 5250);
DOT 1 (5875 5650);
DOT 1 (4975 6050);
DOT 1 (5425 6050);
DOT 1 (5875 6050);
DOT 1 (6350 4075);
DOT 1 (6325 4850);
DOT 1 (6775 4850);
DOT 1 (6325 5250);
DOT 1 (6325 5650);
DOT 1 (6775 5250);
DOT 1 (6775 5650);
DOT 1 (7675 4850);
DOT 1 (7225 4850);
DOT 1 (8125 4850);
DOT 1 (7225 5250);
DOT 1 (7675 5250);
DOT 1 (7225 5650);
DOT 1 (7675 5650);
DOT 1 (8125 5250);
DOT 1 (8125 5650);
DOT 1 (6325 6050);
DOT 1 (6775 6050);
DOT 1 (7225 6050);
DOT 1 (7675 6050);
DOT 1 (8125 6050);
DOT 1 (8600 1150);
DOT 1 (8600 1550);
DOT 1 (8600 1800);
DOT 1 (9000 1150);
DOT 1 (9000 1800);
DOT 1 (8600 2200);
DOT 1 (8600 2425);
DOT 1 (8600 2825);
DOT 1 (9000 2425);
DOT 1 (8600 3100);
DOT 1 (8600 3500);
DOT 1 (9000 3100);
DOT 1 (8575 4850);
DOT 1 (8975 4850);
DOT 1 (8575 5250);
DOT 1 (8575 5650);
DOT 1 (8975 5650);
DOT 1 (8575 6050);
DOT 1 (850 6050);
DOT 1 (400 6050);
DOT 1 (4400 3625);
FORCENOTE
PVDDCR_SOC_P1: 77PCS 22UF ON BOT
(400 6275) 0;
DISPLAY LEFT (400 6275);
DISPLAY 2.510638 (400 6275);
PAINT WHITE (400 6275);
FORCENOTE
5
(2175 1300) 0;
DISPLAY LEFT (2175 1300);
DISPLAY 1.021277 (2175 1300);
PAINT SKYBLUE (2175 1300);
FORCENOTE
5
(2175 2025) 0;
DISPLAY LEFT (2175 2025);
DISPLAY 1.021277 (2175 2025);
PAINT SKYBLUE (2175 2025);
FORCENOTE
5
(2200 2700) 0;
DISPLAY LEFT (2200 2700);
DISPLAY 1.021277 (2200 2700);
PAINT SKYBLUE (2200 2700);
FORCENOTE
5
(2175 3375) 0;
DISPLAY LEFT (2175 3375);
DISPLAY 1.021277 (2175 3375);
PAINT SKYBLUE (2175 3375);
FORCENOTE
5
(2175 4075) 0;
DISPLAY LEFT (2175 4075);
DISPLAY 1.021277 (2175 4075);
PAINT SKYBLUE (2175 4075);
FORCENOTE
5
(2200 4750) 0;
DISPLAY LEFT (2200 4750);
DISPLAY 1.021277 (2200 4750);
PAINT SKYBLUE (2200 4750);
FORCENOTE
5
(2175 5450) 0;
DISPLAY LEFT (2175 5450);
DISPLAY 1.021277 (2175 5450);
PAINT SKYBLUE (2175 5450);
FORCENOTE
5
(2175 6100) 0;
DISPLAY LEFT (2175 6100);
DISPLAY 1.021277 (2175 6100);
PAINT SKYBLUE (2175 6100);
FORCENOTE
10
(4350 2000) 0;
DISPLAY LEFT (4350 2000);
DISPLAY 1.021277 (4350 2000);
PAINT SKYBLUE (4350 2000);
FORCENOTE
10
(4375 2675) 0;
DISPLAY LEFT (4375 2675);
DISPLAY 1.021277 (4375 2675);
PAINT SKYBLUE (4375 2675);
FORCENOTE
10
(4375 3350) 0;
DISPLAY LEFT (4375 3350);
DISPLAY 1.021277 (4375 3350);
PAINT SKYBLUE (4375 3350);
FORCENOTE
5
(6775 1600) 0;
DISPLAY LEFT (6775 1600);
DISPLAY 1.021277 (6775 1600);
PAINT SKYBLUE (6775 1600);
FORCENOTE
5
(6775 2250) 0;
DISPLAY LEFT (6775 2250);
DISPLAY 1.021277 (6775 2250);
PAINT SKYBLUE (6775 2250);
FORCENOTE
5
(6775 2850) 0;
DISPLAY LEFT (6775 2850);
DISPLAY 1.021277 (6775 2850);
PAINT SKYBLUE (6775 2850);
FORCENOTE
5
(6775 3525) 0;
DISPLAY LEFT (6775 3525);
DISPLAY 1.021277 (6775 3525);
PAINT SKYBLUE (6775 3525);
FORCENOTE
10
(4375 4050) 0;
DISPLAY LEFT (4375 4050);
DISPLAY 1.021277 (4375 4050);
PAINT SKYBLUE (4375 4050);
FORCENOTE
10
(4350 4750) 0;
DISPLAY LEFT (4350 4750);
DISPLAY 1.021277 (4350 4750);
PAINT SKYBLUE (4350 4750);
FORCENOTE
10
(4350 5425) 0;
DISPLAY LEFT (4350 5425);
DISPLAY 1.021277 (4350 5425);
PAINT SKYBLUE (4350 5425);
FORCENOTE
10
(4350 6100) 0;
DISPLAY LEFT (4350 6100);
DISPLAY 1.021277 (4350 6100);
PAINT SKYBLUE (4350 6100);
FORCENOTE
5
(6750 5300) 0;
DISPLAY LEFT (6750 5300);
DISPLAY 1.021277 (6750 5300);
PAINT SKYBLUE (6750 5300);
FORCENOTE
5
(6750 6100) 0;
DISPLAY LEFT (6750 6100);
DISPLAY 1.021277 (6750 6100);
PAINT SKYBLUE (6750 6100);
FORCENOTE
PVDD11_S3_P1: 42PCS 22UF ON BOT
(5375 3625) 0;
DISPLAY LEFT (5375 3625);
DISPLAY 2.510638 (5375 3625);
PAINT WHITE (5375 3625);
FORCENOTE
10
(8950 2225) 0;
DISPLAY LEFT (8950 2225);
DISPLAY 1.021277 (8950 2225);
PAINT SKYBLUE (8950 2225);
FORCENOTE
10
(8950 2850) 0;
DISPLAY LEFT (8950 2850);
DISPLAY 1.021277 (8950 2850);
PAINT SKYBLUE (8950 2850);
FORCENOTE
10
(8950 3525) 0;
DISPLAY LEFT (8950 3525);
DISPLAY 1.021277 (8950 3525);
PAINT SKYBLUE (8950 3525);
FORCENOTE
10
(8925 5300) 0;
DISPLAY LEFT (8925 5300);
DISPLAY 1.021277 (8925 5300);
PAINT SKYBLUE (8925 5300);
FORCENOTE
10
(8925 6100) 0;
DISPLAY LEFT (8925 6100);
DISPLAY 1.021277 (8925 6100);
PAINT SKYBLUE (8925 6100);
FORCENOTE
PVDDIO_P1: 24PCS 22UF ON BOT
(4950 6275) 0;
DISPLAY LEFT (4950 6275);
DISPLAY 2.510638 (4950 6275);
PAINT WHITE (4950 6275);
QUIT
